FILE_TYPE = MACRO_DRAWING;
SET COLOR_WIRE YELLOW;
SET COLOR_PROP ORANGE;
SET COLOR_DOT WHITE;
SET COLOR_ARC YELLOW;
SET COLOR_BODY GREEN;
SET COLOR_NOTE PURPLE;
SET PROP_DISPLAY VALUE;
SET PAGE_NUMBER P41;
FORCEADD UNIVERSAL_GND..1
(-3225 -575);
FORCEPROP 3 LASTPIN (-3225 -525) SIG_NAME GND\g
J 0
(-3215 -515);
DISPLAY 0.659574 (-3215 -515);
PAINT MONO (-3215 -515);
DISPLAY INVISIBLE (-3215 -515);
FORCEPROP 2 LAST CDS_LIB logical_power
J 0
(-3225 -575);
PAINT MONO (-3225 -575);
DISPLAY INVISIBLE (-3225 -575);
FORCEPROP 1 LAST HDL_POWER GND
J 1
(-3200 -650);
DISPLAY 0.872340 (-3200 -650);
PAINT GREEN (-3200 -650);
DISPLAY INVISIBLE (-3200 -650);
FORCEPROP 1 LAST PATH I1
J 0
(-3150 -575);
DISPLAY 0.872340 (-3150 -575);
PAINT AQUA (-3150 -575);
DISPLAY INVISIBLE (-3150 -575);
FORCEADD SOCKET4677_AZIF0045P001C01CS..38
(1275 1950);
FORCEPROP 1 LAST PART_NUMBER DGA^7000023
J 0
(225 4200);
DISPLAY 0.723404 (225 4200);
PAINT GREEN (225 4200);
DISPLAY INVISIBLE (225 4200);
FORCEPROP 2 LAST PART_TYPE SMLF
J 0
(225 4375);
DISPLAY 1.021277 (225 4375);
FORCEPROP 1 LAST MATERIAL IO
J 0
(225 4125);
DISPLAY 0.723404 (225 4125);
PAINT GREEN (225 4125);
FORCEPROP 2 LAST VALUE SOCKET4677_AZIF0045-P001C01CS
J 0
(225 4325);
DISPLAY 1.021277 (225 4325);
FORCEPROP 1 LAST $LOCATION U2
J 0
(225 4275);
DISPLAY 0.723404 (225 4275);
PAINT GREEN (225 4275);
FORCEPROP 0 LASTPIN (2475 75) $PN AK12
J 0
(2485 85);
DISPLAY 0.680851 (2485 85);
PAINT MONO (2485 85);
FORCEPROP 0 LASTPIN (2475 125) $PN AK16
J 0
(2485 135);
DISPLAY 0.680851 (2485 135);
PAINT MONO (2485 135);
FORCEPROP 0 LASTPIN (2475 175) $PN AK18
J 0
(2485 185);
DISPLAY 0.680851 (2485 185);
PAINT MONO (2485 185);
FORCEPROP 0 LASTPIN (2475 225) $PN AK24
J 0
(2485 235);
DISPLAY 0.680851 (2485 235);
PAINT MONO (2485 235);
FORCEPROP 0 LASTPIN (2475 275) $PN AK30
J 0
(2485 285);
DISPLAY 0.680851 (2485 285);
PAINT MONO (2485 285);
FORCEPROP 0 LASTPIN (2475 325) $PN AK36
J 0
(2485 335);
DISPLAY 0.680851 (2485 335);
PAINT MONO (2485 335);
FORCEPROP 0 LASTPIN (2475 -25) $PN AK4
J 0
(2485 -15);
DISPLAY 0.680851 (2485 -15);
PAINT MONO (2485 -15);
FORCEPROP 0 LASTPIN (2475 375) $PN AK42
J 0
(2485 385);
DISPLAY 0.680851 (2485 385);
PAINT MONO (2485 385);
FORCEPROP 0 LASTPIN (2475 425) $PN AK49
J 0
(2485 435);
DISPLAY 0.680851 (2485 435);
PAINT MONO (2485 435);
FORCEPROP 0 LASTPIN (2475 475) $PN AK55
J 0
(2485 485);
DISPLAY 0.680851 (2485 485);
PAINT MONO (2485 485);
FORCEPROP 0 LASTPIN (2475 525) $PN AK61
J 0
(2485 535);
DISPLAY 0.680851 (2485 535);
PAINT MONO (2485 535);
FORCEPROP 0 LASTPIN (2475 575) $PN AK67
J 0
(2485 585);
DISPLAY 0.680851 (2485 585);
PAINT MONO (2485 585);
FORCEPROP 0 LASTPIN (2475 625) $PN AK73
J 0
(2485 635);
DISPLAY 0.680851 (2485 635);
PAINT MONO (2485 635);
FORCEPROP 0 LASTPIN (2475 675) $PN AK79
J 0
(2485 685);
DISPLAY 0.680851 (2485 685);
PAINT MONO (2485 685);
FORCEPROP 0 LASTPIN (2475 25) $PN AK8
J 0
(2485 35);
DISPLAY 0.680851 (2485 35);
PAINT MONO (2485 35);
FORCEPROP 0 LASTPIN (2475 725) $PN AK81
J 0
(2485 735);
DISPLAY 0.680851 (2485 735);
PAINT MONO (2485 735);
FORCEPROP 0 LASTPIN (2475 775) $PN AK83
J 0
(2485 785);
DISPLAY 0.680851 (2485 785);
PAINT MONO (2485 785);
FORCEPROP 0 LASTPIN (2475 825) $PN AK87
J 0
(2485 835);
DISPLAY 0.680851 (2485 835);
PAINT MONO (2485 835);
FORCEPROP 0 LASTPIN (2475 875) $PN AK91
J 0
(2485 885);
DISPLAY 0.680851 (2485 885);
PAINT MONO (2485 885);
FORCEPROP 0 LASTPIN (2475 925) $PN AL1
J 0
(2485 935);
DISPLAY 0.680851 (2485 935);
PAINT MONO (2485 935);
FORCEPROP 0 LASTPIN (2475 1075) $PN AL13
J 0
(2485 1085);
DISPLAY 0.680851 (2485 1085);
PAINT MONO (2485 1085);
FORCEPROP 0 LASTPIN (2475 1125) $PN AL17
J 0
(2485 1135);
DISPLAY 0.680851 (2485 1135);
PAINT MONO (2485 1135);
FORCEPROP 0 LASTPIN (2475 975) $PN AL5
J 0
(2485 985);
DISPLAY 0.680851 (2485 985);
PAINT MONO (2485 985);
FORCEPROP 0 LASTPIN (2475 1175) $PN AL52
J 0
(2485 1185);
DISPLAY 0.680851 (2485 1185);
PAINT MONO (2485 1185);
FORCEPROP 0 LASTPIN (2475 1225) $PN AL80
J 0
(2485 1235);
DISPLAY 0.680851 (2485 1235);
PAINT MONO (2485 1235);
FORCEPROP 0 LASTPIN (2475 1275) $PN AL82
J 0
(2485 1285);
DISPLAY 0.680851 (2485 1285);
PAINT MONO (2485 1285);
FORCEPROP 0 LASTPIN (2475 1325) $PN AL84
J 0
(2485 1335);
DISPLAY 0.680851 (2485 1335);
PAINT MONO (2485 1335);
FORCEPROP 0 LASTPIN (2475 1375) $PN AL88
J 0
(2485 1385);
DISPLAY 0.680851 (2485 1385);
PAINT MONO (2485 1385);
FORCEPROP 0 LASTPIN (2475 1025) $PN AL9
J 0
(2485 1035);
DISPLAY 0.680851 (2485 1035);
PAINT MONO (2485 1035);
FORCEPROP 0 LASTPIN (2475 1525) $PN AM12
J 0
(2485 1535);
DISPLAY 0.680851 (2485 1535);
PAINT MONO (2485 1535);
FORCEPROP 0 LASTPIN (2475 1575) $PN AM16
J 0
(2485 1585);
DISPLAY 0.680851 (2485 1585);
PAINT MONO (2485 1585);
FORCEPROP 0 LASTPIN (2475 1625) $PN AM18
J 0
(2485 1635);
DISPLAY 0.680851 (2485 1635);
PAINT MONO (2485 1635);
FORCEPROP 0 LASTPIN (2475 1675) $PN AM20
J 0
(2485 1685);
DISPLAY 0.680851 (2485 1685);
PAINT MONO (2485 1685);
FORCEPROP 0 LASTPIN (2475 1725) $PN AM22
J 0
(2485 1735);
DISPLAY 0.680851 (2485 1735);
PAINT MONO (2485 1735);
FORCEPROP 0 LASTPIN (2475 1775) $PN AM24
J 0
(2485 1785);
DISPLAY 0.680851 (2485 1785);
PAINT MONO (2485 1785);
FORCEPROP 0 LASTPIN (2475 1825) $PN AM26
J 0
(2485 1835);
DISPLAY 0.680851 (2485 1835);
PAINT MONO (2485 1835);
FORCEPROP 0 LASTPIN (2475 1875) $PN AM28
J 0
(2485 1885);
DISPLAY 0.680851 (2485 1885);
PAINT MONO (2485 1885);
FORCEPROP 0 LASTPIN (2475 1925) $PN AM30
J 0
(2485 1935);
DISPLAY 0.680851 (2485 1935);
PAINT MONO (2485 1935);
FORCEPROP 0 LASTPIN (2475 1975) $PN AM32
J 0
(2485 1985);
DISPLAY 0.680851 (2485 1985);
PAINT MONO (2485 1985);
FORCEPROP 0 LASTPIN (2475 2025) $PN AM34
J 0
(2485 2035);
DISPLAY 0.680851 (2485 2035);
PAINT MONO (2485 2035);
FORCEPROP 0 LASTPIN (2475 2075) $PN AM36
J 0
(2485 2085);
DISPLAY 0.680851 (2485 2085);
PAINT MONO (2485 2085);
FORCEPROP 0 LASTPIN (2475 2125) $PN AM38
J 0
(2485 2135);
DISPLAY 0.680851 (2485 2135);
PAINT MONO (2485 2135);
FORCEPROP 0 LASTPIN (2475 1425) $PN AM4
J 0
(2485 1435);
DISPLAY 0.680851 (2485 1435);
PAINT MONO (2485 1435);
FORCEPROP 0 LASTPIN (2475 2175) $PN AM40
J 0
(2485 2185);
DISPLAY 0.680851 (2485 2185);
PAINT MONO (2485 2185);
FORCEPROP 0 LASTPIN (2475 2225) $PN AM42
J 0
(2485 2235);
DISPLAY 0.680851 (2485 2235);
PAINT MONO (2485 2235);
FORCEPROP 0 LASTPIN (2475 2275) $PN AM44
J 0
(2485 2285);
DISPLAY 0.680851 (2485 2285);
PAINT MONO (2485 2285);
FORCEPROP 0 LASTPIN (2475 2325) $PN AM47
J 0
(2485 2335);
DISPLAY 0.680851 (2485 2335);
PAINT MONO (2485 2335);
FORCEPROP 0 LASTPIN (2475 2375) $PN AM49
J 0
(2485 2385);
DISPLAY 0.680851 (2485 2385);
PAINT MONO (2485 2385);
FORCEPROP 0 LASTPIN (2475 2425) $PN AM51
J 0
(2485 2435);
DISPLAY 0.680851 (2485 2435);
PAINT MONO (2485 2435);
FORCEPROP 0 LASTPIN (2475 2475) $PN AM53
J 0
(2485 2485);
DISPLAY 0.680851 (2485 2485);
PAINT MONO (2485 2485);
FORCEPROP 0 LASTPIN (2475 2525) $PN AM55
J 0
(2485 2535);
DISPLAY 0.680851 (2485 2535);
PAINT MONO (2485 2535);
FORCEPROP 0 LASTPIN (2475 2575) $PN AM57
J 0
(2485 2585);
DISPLAY 0.680851 (2485 2585);
PAINT MONO (2485 2585);
FORCEPROP 0 LASTPIN (2475 2625) $PN AM59
J 0
(2485 2635);
DISPLAY 0.680851 (2485 2635);
PAINT MONO (2485 2635);
FORCEPROP 0 LASTPIN (2475 2675) $PN AM61
J 0
(2485 2685);
DISPLAY 0.680851 (2485 2685);
PAINT MONO (2485 2685);
FORCEPROP 0 LASTPIN (2475 2725) $PN AM63
J 0
(2485 2735);
DISPLAY 0.680851 (2485 2735);
PAINT MONO (2485 2735);
FORCEPROP 0 LASTPIN (2475 2775) $PN AM65
J 0
(2485 2785);
DISPLAY 0.680851 (2485 2785);
PAINT MONO (2485 2785);
FORCEPROP 0 LASTPIN (2475 2825) $PN AM67
J 0
(2485 2835);
DISPLAY 0.680851 (2485 2835);
PAINT MONO (2485 2835);
FORCEPROP 0 LASTPIN (2475 2875) $PN AM69
J 0
(2485 2885);
DISPLAY 0.680851 (2485 2885);
PAINT MONO (2485 2885);
FORCEPROP 0 LASTPIN (2475 2925) $PN AM71
J 0
(2485 2935);
DISPLAY 0.680851 (2485 2935);
PAINT MONO (2485 2935);
FORCEPROP 0 LASTPIN (2475 2975) $PN AM73
J 0
(2485 2985);
DISPLAY 0.680851 (2485 2985);
PAINT MONO (2485 2985);
FORCEPROP 0 LASTPIN (2475 3025) $PN AM75
J 0
(2485 3035);
DISPLAY 0.680851 (2485 3035);
PAINT MONO (2485 3035);
FORCEPROP 0 LASTPIN (2475 3075) $PN AM77
J 0
(2485 3085);
DISPLAY 0.680851 (2485 3085);
PAINT MONO (2485 3085);
FORCEPROP 0 LASTPIN (2475 1475) $PN AM8
J 0
(2485 1485);
DISPLAY 0.680851 (2485 1485);
PAINT MONO (2485 1485);
FORCEPROP 0 LASTPIN (2475 3125) $PN AN52
J 0
(2485 3135);
DISPLAY 0.680851 (2485 3135);
PAINT MONO (2485 3135);
FORCEPROP 0 LASTPIN (2475 3175) $PN AN84
J 0
(2485 3185);
DISPLAY 0.680851 (2485 3185);
PAINT MONO (2485 3185);
FORCEPROP 0 LASTPIN (2475 3225) $PN AN88
J 0
(2485 3235);
DISPLAY 0.680851 (2485 3235);
PAINT MONO (2485 3235);
FORCEPROP 0 LASTPIN (2475 3375) $PN AP12
J 0
(2485 3385);
DISPLAY 0.680851 (2485 3385);
PAINT MONO (2485 3385);
FORCEPROP 0 LASTPIN (2475 3425) $PN AP16
J 0
(2485 3435);
DISPLAY 0.680851 (2485 3435);
PAINT MONO (2485 3435);
FORCEPROP 0 LASTPIN (2475 3475) $PN AP18
J 0
(2485 3485);
DISPLAY 0.680851 (2485 3485);
PAINT MONO (2485 3485);
FORCEPROP 0 LASTPIN (2475 3525) $PN AP24
J 0
(2485 3535);
DISPLAY 0.680851 (2485 3535);
PAINT MONO (2485 3535);
FORCEPROP 0 LASTPIN (2475 3575) $PN AP30
J 0
(2485 3585);
DISPLAY 0.680851 (2485 3585);
PAINT MONO (2485 3585);
FORCEPROP 0 LASTPIN (2475 3625) $PN AP36
J 0
(2485 3635);
DISPLAY 0.680851 (2485 3635);
PAINT MONO (2485 3635);
FORCEPROP 0 LASTPIN (2475 3275) $PN AP4
J 0
(2485 3285);
DISPLAY 0.680851 (2485 3285);
PAINT MONO (2485 3285);
FORCEPROP 0 LASTPIN (2475 3675) $PN AP42
J 0
(2485 3685);
DISPLAY 0.680851 (2485 3685);
PAINT MONO (2485 3685);
FORCEPROP 0 LASTPIN (2475 3725) $PN AP49
J 0
(2485 3735);
DISPLAY 0.680851 (2485 3735);
PAINT MONO (2485 3735);
FORCEPROP 0 LASTPIN (2475 3775) $PN AP55
J 0
(2485 3785);
DISPLAY 0.680851 (2485 3785);
PAINT MONO (2485 3785);
FORCEPROP 0 LASTPIN (2475 3825) $PN AP61
J 0
(2485 3835);
DISPLAY 0.680851 (2485 3835);
PAINT MONO (2485 3835);
FORCEPROP 0 LASTPIN (2475 3875) $PN AP67
J 0
(2485 3885);
DISPLAY 0.680851 (2485 3885);
PAINT MONO (2485 3885);
FORCEPROP 0 LASTPIN (2475 3925) $PN AP73
J 0
(2485 3935);
DISPLAY 0.680851 (2485 3935);
PAINT MONO (2485 3935);
FORCEPROP 0 LASTPIN (75 -25) $PN AP79
J 2
(65 -15);
DISPLAY 0.680851 (65 -15);
PAINT MONO (65 -15);
FORCEPROP 0 LASTPIN (2475 3325) $PN AP8
J 0
(2485 3335);
DISPLAY 0.680851 (2485 3335);
PAINT MONO (2485 3335);
FORCEPROP 0 LASTPIN (75 25) $PN AP83
J 2
(65 35);
DISPLAY 0.680851 (65 35);
PAINT MONO (65 35);
FORCEPROP 0 LASTPIN (75 75) $PN AP87
J 2
(65 85);
DISPLAY 0.680851 (65 85);
PAINT MONO (65 85);
FORCEPROP 0 LASTPIN (75 125) $PN AP91
J 2
(65 135);
DISPLAY 0.680851 (65 135);
PAINT MONO (65 135);
FORCEPROP 0 LASTPIN (75 175) $PN AR1
J 2
(65 185);
DISPLAY 0.680851 (65 185);
PAINT MONO (65 185);
FORCEPROP 0 LASTPIN (75 325) $PN AR13
J 2
(65 335);
DISPLAY 0.680851 (65 335);
PAINT MONO (65 335);
FORCEPROP 0 LASTPIN (75 375) $PN AR19
J 2
(65 385);
DISPLAY 0.680851 (65 385);
PAINT MONO (65 385);
FORCEPROP 0 LASTPIN (75 425) $PN AR23
J 2
(65 435);
DISPLAY 0.680851 (65 435);
PAINT MONO (65 435);
FORCEPROP 0 LASTPIN (75 475) $PN AR25
J 2
(65 485);
DISPLAY 0.680851 (65 485);
PAINT MONO (65 485);
FORCEPROP 0 LASTPIN (75 525) $PN AR29
J 2
(65 535);
DISPLAY 0.680851 (65 535);
PAINT MONO (65 535);
FORCEPROP 0 LASTPIN (75 575) $PN AR31
J 2
(65 585);
DISPLAY 0.680851 (65 585);
PAINT MONO (65 585);
FORCEPROP 0 LASTPIN (75 625) $PN AR35
J 2
(65 635);
DISPLAY 0.680851 (65 635);
PAINT MONO (65 635);
FORCEPROP 0 LASTPIN (75 675) $PN AR37
J 2
(65 685);
DISPLAY 0.680851 (65 685);
PAINT MONO (65 685);
FORCEPROP 0 LASTPIN (75 725) $PN AR41
J 2
(65 735);
DISPLAY 0.680851 (65 735);
PAINT MONO (65 735);
FORCEPROP 0 LASTPIN (75 775) $PN AR43
J 2
(65 785);
DISPLAY 0.680851 (65 785);
PAINT MONO (65 785);
FORCEPROP 0 LASTPIN (75 825) $PN AR48
J 2
(65 835);
DISPLAY 0.680851 (65 835);
PAINT MONO (65 835);
FORCEPROP 0 LASTPIN (75 225) $PN AR5
J 2
(65 235);
DISPLAY 0.680851 (65 235);
PAINT MONO (65 235);
FORCEPROP 0 LASTPIN (75 875) $PN AR50
J 2
(65 885);
DISPLAY 0.680851 (65 885);
PAINT MONO (65 885);
FORCEPROP 0 LASTPIN (75 925) $PN AR54
J 2
(65 935);
DISPLAY 0.680851 (65 935);
PAINT MONO (65 935);
FORCEPROP 0 LASTPIN (75 975) $PN AR56
J 2
(65 985);
DISPLAY 0.680851 (65 985);
PAINT MONO (65 985);
FORCEPROP 0 LASTPIN (75 1025) $PN AR60
J 2
(65 1035);
DISPLAY 0.680851 (65 1035);
PAINT MONO (65 1035);
FORCEPROP 0 LASTPIN (75 1075) $PN AR62
J 2
(65 1085);
DISPLAY 0.680851 (65 1085);
PAINT MONO (65 1085);
FORCEPROP 0 LASTPIN (75 1125) $PN AR66
J 2
(65 1135);
DISPLAY 0.680851 (65 1135);
PAINT MONO (65 1135);
FORCEPROP 0 LASTPIN (75 1175) $PN AR68
J 2
(65 1185);
DISPLAY 0.680851 (65 1185);
PAINT MONO (65 1185);
FORCEPROP 0 LASTPIN (75 1225) $PN AR72
J 2
(65 1235);
DISPLAY 0.680851 (65 1235);
PAINT MONO (65 1235);
FORCEPROP 0 LASTPIN (75 1275) $PN AR74
J 2
(65 1285);
DISPLAY 0.680851 (65 1285);
PAINT MONO (65 1285);
FORCEPROP 0 LASTPIN (75 1325) $PN AR78
J 2
(65 1335);
DISPLAY 0.680851 (65 1335);
PAINT MONO (65 1335);
FORCEPROP 0 LASTPIN (75 1375) $PN AR82
J 2
(65 1385);
DISPLAY 0.680851 (65 1385);
PAINT MONO (65 1385);
FORCEPROP 0 LASTPIN (75 1425) $PN AR84
J 2
(65 1435);
DISPLAY 0.680851 (65 1435);
PAINT MONO (65 1435);
FORCEPROP 0 LASTPIN (75 1475) $PN AR88
J 2
(65 1485);
DISPLAY 0.680851 (65 1485);
PAINT MONO (65 1485);
FORCEPROP 0 LASTPIN (75 275) $PN AR9
J 2
(65 285);
DISPLAY 0.680851 (65 285);
PAINT MONO (65 285);
FORCEPROP 0 LASTPIN (75 1625) $PN AT12
J 2
(65 1635);
DISPLAY 0.680851 (65 1635);
PAINT MONO (65 1635);
FORCEPROP 0 LASTPIN (75 1675) $PN AT16
J 2
(65 1685);
DISPLAY 0.680851 (65 1685);
PAINT MONO (65 1685);
FORCEPROP 0 LASTPIN (75 1725) $PN AT20
J 2
(65 1735);
DISPLAY 0.680851 (65 1735);
PAINT MONO (65 1735);
FORCEPROP 0 LASTPIN (75 1775) $PN AT22
J 2
(65 1785);
DISPLAY 0.680851 (65 1785);
PAINT MONO (65 1785);
FORCEPROP 0 LASTPIN (75 1825) $PN AT26
J 2
(65 1835);
DISPLAY 0.680851 (65 1835);
PAINT MONO (65 1835);
FORCEPROP 0 LASTPIN (75 1875) $PN AT28
J 2
(65 1885);
DISPLAY 0.680851 (65 1885);
PAINT MONO (65 1885);
FORCEPROP 0 LASTPIN (75 1925) $PN AT32
J 2
(65 1935);
DISPLAY 0.680851 (65 1935);
PAINT MONO (65 1935);
FORCEPROP 0 LASTPIN (75 1975) $PN AT34
J 2
(65 1985);
DISPLAY 0.680851 (65 1985);
PAINT MONO (65 1985);
FORCEPROP 0 LASTPIN (75 2025) $PN AT38
J 2
(65 2035);
DISPLAY 0.680851 (65 2035);
PAINT MONO (65 2035);
FORCEPROP 0 LASTPIN (75 1525) $PN AT4
J 2
(65 1535);
DISPLAY 0.680851 (65 1535);
PAINT MONO (65 1535);
FORCEPROP 0 LASTPIN (75 2075) $PN AT40
J 2
(65 2085);
DISPLAY 0.680851 (65 2085);
PAINT MONO (65 2085);
FORCEPROP 0 LASTPIN (75 2125) $PN AT44
J 2
(65 2135);
DISPLAY 0.680851 (65 2135);
PAINT MONO (65 2135);
FORCEPROP 0 LASTPIN (75 2175) $PN AT51
J 2
(65 2185);
DISPLAY 0.680851 (65 2185);
PAINT MONO (65 2185);
FORCEPROP 0 LASTPIN (75 2225) $PN AT53
J 2
(65 2235);
DISPLAY 0.680851 (65 2235);
PAINT MONO (65 2235);
FORCEPROP 0 LASTPIN (75 2275) $PN AT57
J 2
(65 2285);
DISPLAY 0.680851 (65 2285);
PAINT MONO (65 2285);
FORCEPROP 0 LASTPIN (75 2325) $PN AT59
J 2
(65 2335);
DISPLAY 0.680851 (65 2335);
PAINT MONO (65 2335);
FORCEPROP 0 LASTPIN (75 2375) $PN AT63
J 2
(65 2385);
DISPLAY 0.680851 (65 2385);
PAINT MONO (65 2385);
FORCEPROP 0 LASTPIN (75 2425) $PN AT65
J 2
(65 2435);
DISPLAY 0.680851 (65 2435);
PAINT MONO (65 2435);
FORCEPROP 0 LASTPIN (75 2475) $PN AT69
J 2
(65 2485);
DISPLAY 0.680851 (65 2485);
PAINT MONO (65 2485);
FORCEPROP 0 LASTPIN (75 2525) $PN AT71
J 2
(65 2535);
DISPLAY 0.680851 (65 2535);
PAINT MONO (65 2535);
FORCEPROP 0 LASTPIN (75 2575) $PN AT75
J 2
(65 2585);
DISPLAY 0.680851 (65 2585);
PAINT MONO (65 2585);
FORCEPROP 0 LASTPIN (75 2625) $PN AT77
J 2
(65 2635);
DISPLAY 0.680851 (65 2635);
PAINT MONO (65 2635);
FORCEPROP 0 LASTPIN (75 2675) $PN AT79
J 2
(65 2685);
DISPLAY 0.680851 (65 2685);
PAINT MONO (65 2685);
FORCEPROP 0 LASTPIN (75 1575) $PN AT8
J 2
(65 1585);
DISPLAY 0.680851 (65 1585);
PAINT MONO (65 1585);
FORCEPROP 0 LASTPIN (75 2725) $PN AU27
J 2
(65 2735);
DISPLAY 0.680851 (65 2735);
PAINT MONO (65 2735);
FORCEPROP 0 LASTPIN (75 2775) $PN AU31
J 2
(65 2785);
DISPLAY 0.680851 (65 2785);
PAINT MONO (65 2785);
FORCEPROP 0 LASTPIN (75 2825) $PN AU37
J 2
(65 2835);
DISPLAY 0.680851 (65 2835);
PAINT MONO (65 2835);
FORCEPROP 0 LASTPIN (75 2875) $PN AU39
J 2
(65 2885);
DISPLAY 0.680851 (65 2885);
PAINT MONO (65 2885);
FORCEPROP 0 LASTPIN (75 2925) $PN AU41
J 2
(65 2935);
DISPLAY 0.680851 (65 2935);
PAINT MONO (65 2935);
FORCEPROP 0 LASTPIN (75 2975) $PN AU45
J 2
(65 2985);
DISPLAY 0.680851 (65 2985);
PAINT MONO (65 2985);
FORCEPROP 0 LASTPIN (75 3025) $PN AU48
J 2
(65 3035);
DISPLAY 0.680851 (65 3035);
PAINT MONO (65 3035);
FORCEPROP 0 LASTPIN (75 3075) $PN AU70
J 2
(65 3085);
DISPLAY 0.680851 (65 3085);
PAINT MONO (65 3085);
FORCEPROP 0 LASTPIN (75 3125) $PN AU72
J 2
(65 3135);
DISPLAY 0.680851 (65 3135);
PAINT MONO (65 3135);
FORCEPROP 0 LASTPIN (75 3175) $PN AU74
J 2
(65 3185);
DISPLAY 0.680851 (65 3185);
PAINT MONO (65 3185);
FORCEPROP 0 LASTPIN (75 3225) $PN AU76
J 2
(65 3235);
DISPLAY 0.680851 (65 3235);
PAINT MONO (65 3235);
FORCEPROP 0 LASTPIN (75 3275) $PN AU80
J 2
(65 3285);
DISPLAY 0.680851 (65 3285);
PAINT MONO (65 3285);
FORCEPROP 0 LASTPIN (75 3325) $PN AU84
J 2
(65 3335);
DISPLAY 0.680851 (65 3335);
PAINT MONO (65 3335);
FORCEPROP 0 LASTPIN (75 3375) $PN AU88
J 2
(65 3385);
DISPLAY 0.680851 (65 3385);
PAINT MONO (65 3385);
FORCEPROP 0 LASTPIN (75 3525) $PN AV12
J 2
(65 3535);
DISPLAY 0.680851 (65 3535);
PAINT MONO (65 3535);
FORCEPROP 0 LASTPIN (75 3575) $PN AV16
J 2
(65 3585);
DISPLAY 0.680851 (65 3585);
PAINT MONO (65 3585);
FORCEPROP 0 LASTPIN (75 3425) $PN AV4
J 2
(65 3435);
DISPLAY 0.680851 (65 3435);
PAINT MONO (65 3435);
FORCEPROP 0 LASTPIN (75 3625) $PN AV77
J 2
(65 3635);
DISPLAY 0.680851 (65 3635);
PAINT MONO (65 3635);
FORCEPROP 0 LASTPIN (75 3475) $PN AV8
J 2
(65 3485);
DISPLAY 0.680851 (65 3485);
PAINT MONO (65 3485);
FORCEPROP 0 LASTPIN (75 3675) $PN AV87
J 2
(65 3685);
DISPLAY 0.680851 (65 3685);
PAINT MONO (65 3685);
FORCEPROP 0 LASTPIN (75 3725) $PN AV91
J 2
(65 3735);
DISPLAY 0.680851 (65 3735);
PAINT MONO (65 3735);
FORCEPROP 0 LASTPIN (75 3775) $PN AW1
J 2
(65 3785);
DISPLAY 0.680851 (65 3785);
PAINT MONO (65 3785);
FORCEPROP 0 LASTPIN (75 3925) $PN AW13
J 2
(65 3935);
DISPLAY 0.680851 (65 3935);
PAINT MONO (65 3935);
FORCEPROP 0 LASTPIN (75 3825) $PN AW5
J 2
(65 3835);
DISPLAY 0.680851 (65 3835);
PAINT MONO (65 3835);
FORCEPROP 0 LASTPIN (75 3875) $PN AW9
J 2
(65 3885);
DISPLAY 0.680851 (65 3885);
PAINT MONO (65 3885);
FORCEPROP 2 LAST CDS_LIB pure_quanta
J 0
(1275 1950);
DISPLAY INVISIBLE (1275 1950);
FORCEPROP 1 LAST NEEDS_NO_SIZE TRUE
J 0
(1275 1950);
DISPLAY 0.723404 (1275 1950);
PAINT GREEN (1275 1950);
DISPLAY INVISIBLE (1275 1950);
FORCEPROP 1 LAST CDS_LMAN_SYM_OUTLINE -1050,2150,1050,-2100
J 0
(1275 1950);
DISPLAY 0.468085 (1275 1950);
PAINT GREEN (1275 1950);
DISPLAY INVISIBLE (1275 1950);
FORCEPROP 2 LAST CDS_LOCATION U2
J 0
(225 4425);
DISPLAY 1.021277 (225 4425);
DISPLAY INVISIBLE (225 4425);
FORCEPROP 0 LAST $SEC 38
J 0
(225 4425);
DISPLAY 0.680851 (225 4425);
PAINT MONO (225 4425);
DISPLAY INVISIBLE (225 4425);
FORCEPROP 2 LAST CDS_SEC 38
J 0
(225 4425);
DISPLAY 1.021277 (225 4425);
DISPLAY INVISIBLE (225 4425);
FORCEPROP 1 LAST PATH I10
J 0
(1275 1950);
DISPLAY 0.723404 (1275 1950);
PAINT GREEN (1275 1950);
DISPLAY INVISIBLE (1275 1950);
FORCEADD SOCKET4677_AZIF0045P001C01CS..39
(4300 1950);
FORCEPROP 1 LAST PART_NUMBER DGA^7000023
J 0
(3250 4200);
DISPLAY 0.723404 (3250 4200);
PAINT GREEN (3250 4200);
DISPLAY INVISIBLE (3250 4200);
FORCEPROP 2 LAST PART_TYPE SMLF
J 0
(3250 4375);
DISPLAY 1.021277 (3250 4375);
FORCEPROP 1 LAST MATERIAL IO
J 0
(3250 4125);
DISPLAY 0.723404 (3250 4125);
PAINT GREEN (3250 4125);
FORCEPROP 2 LAST VALUE SOCKET4677_AZIF0045-P001C01CS
J 0
(3250 4325);
DISPLAY 1.021277 (3250 4325);
FORCEPROP 1 LAST $LOCATION U2
J 0
(3250 4275);
DISPLAY 0.723404 (3250 4275);
PAINT GREEN (3250 4275);
FORCEPROP 0 LASTPIN (5500 -25) $PN AA82
J 0
(5510 -15);
DISPLAY 0.680851 (5510 -15);
PAINT MONO (5510 -15);
FORCEPROP 0 LASTPIN (5500 25) $PN AA84
J 0
(5510 35);
DISPLAY 0.680851 (5510 35);
PAINT MONO (5510 35);
FORCEPROP 0 LASTPIN (5500 75) $PN AA88
J 0
(5510 85);
DISPLAY 0.680851 (5510 85);
PAINT MONO (5510 85);
FORCEPROP 0 LASTPIN (5500 225) $PN AB12
J 0
(5510 235);
DISPLAY 0.680851 (5510 235);
PAINT MONO (5510 235);
FORCEPROP 0 LASTPIN (5500 275) $PN AB16
J 0
(5510 285);
DISPLAY 0.680851 (5510 285);
PAINT MONO (5510 285);
FORCEPROP 0 LASTPIN (5500 325) $PN AB20
J 0
(5510 335);
DISPLAY 0.680851 (5510 335);
PAINT MONO (5510 335);
FORCEPROP 0 LASTPIN (5500 375) $PN AB22
J 0
(5510 385);
DISPLAY 0.680851 (5510 385);
PAINT MONO (5510 385);
FORCEPROP 0 LASTPIN (5500 425) $PN AB26
J 0
(5510 435);
DISPLAY 0.680851 (5510 435);
PAINT MONO (5510 435);
FORCEPROP 0 LASTPIN (5500 475) $PN AB28
J 0
(5510 485);
DISPLAY 0.680851 (5510 485);
PAINT MONO (5510 485);
FORCEPROP 0 LASTPIN (5500 525) $PN AB32
J 0
(5510 535);
DISPLAY 0.680851 (5510 535);
PAINT MONO (5510 535);
FORCEPROP 0 LASTPIN (5500 575) $PN AB34
J 0
(5510 585);
DISPLAY 0.680851 (5510 585);
PAINT MONO (5510 585);
FORCEPROP 0 LASTPIN (5500 625) $PN AB38
J 0
(5510 635);
DISPLAY 0.680851 (5510 635);
PAINT MONO (5510 635);
FORCEPROP 0 LASTPIN (5500 125) $PN AB4
J 0
(5510 135);
DISPLAY 0.680851 (5510 135);
PAINT MONO (5510 135);
FORCEPROP 0 LASTPIN (5500 675) $PN AB40
J 0
(5510 685);
DISPLAY 0.680851 (5510 685);
PAINT MONO (5510 685);
FORCEPROP 0 LASTPIN (5500 725) $PN AB44
J 0
(5510 735);
DISPLAY 0.680851 (5510 735);
PAINT MONO (5510 735);
FORCEPROP 0 LASTPIN (5500 775) $PN AB47
J 0
(5510 785);
DISPLAY 0.680851 (5510 785);
PAINT MONO (5510 785);
FORCEPROP 0 LASTPIN (5500 825) $PN AB51
J 0
(5510 835);
DISPLAY 0.680851 (5510 835);
PAINT MONO (5510 835);
FORCEPROP 0 LASTPIN (5500 875) $PN AB53
J 0
(5510 885);
DISPLAY 0.680851 (5510 885);
PAINT MONO (5510 885);
FORCEPROP 0 LASTPIN (5500 925) $PN AB57
J 0
(5510 935);
DISPLAY 0.680851 (5510 935);
PAINT MONO (5510 935);
FORCEPROP 0 LASTPIN (5500 975) $PN AB59
J 0
(5510 985);
DISPLAY 0.680851 (5510 985);
PAINT MONO (5510 985);
FORCEPROP 0 LASTPIN (5500 1025) $PN AB63
J 0
(5510 1035);
DISPLAY 0.680851 (5510 1035);
PAINT MONO (5510 1035);
FORCEPROP 0 LASTPIN (5500 1075) $PN AB65
J 0
(5510 1085);
DISPLAY 0.680851 (5510 1085);
PAINT MONO (5510 1085);
FORCEPROP 0 LASTPIN (5500 1125) $PN AB69
J 0
(5510 1135);
DISPLAY 0.680851 (5510 1135);
PAINT MONO (5510 1135);
FORCEPROP 0 LASTPIN (5500 1175) $PN AB71
J 0
(5510 1185);
DISPLAY 0.680851 (5510 1185);
PAINT MONO (5510 1185);
FORCEPROP 0 LASTPIN (5500 1225) $PN AB75
J 0
(5510 1235);
DISPLAY 0.680851 (5510 1235);
PAINT MONO (5510 1235);
FORCEPROP 0 LASTPIN (5500 1275) $PN AB77
J 0
(5510 1285);
DISPLAY 0.680851 (5510 1285);
PAINT MONO (5510 1285);
FORCEPROP 0 LASTPIN (5500 1325) $PN AB79
J 0
(5510 1335);
DISPLAY 0.680851 (5510 1335);
PAINT MONO (5510 1335);
FORCEPROP 0 LASTPIN (5500 175) $PN AB8
J 0
(5510 185);
DISPLAY 0.680851 (5510 185);
PAINT MONO (5510 185);
FORCEPROP 0 LASTPIN (5500 1375) $PN AB81
J 0
(5510 1385);
DISPLAY 0.680851 (5510 1385);
PAINT MONO (5510 1385);
FORCEPROP 0 LASTPIN (5500 1425) $PN AB83
J 0
(5510 1435);
DISPLAY 0.680851 (5510 1435);
PAINT MONO (5510 1435);
FORCEPROP 0 LASTPIN (5500 1475) $PN AB87
J 0
(5510 1485);
DISPLAY 0.680851 (5510 1485);
PAINT MONO (5510 1485);
FORCEPROP 0 LASTPIN (5500 1525) $PN AB91
J 0
(5510 1535);
DISPLAY 0.680851 (5510 1535);
PAINT MONO (5510 1535);
FORCEPROP 0 LASTPIN (5500 1575) $PN AC1
J 0
(5510 1585);
DISPLAY 0.680851 (5510 1585);
PAINT MONO (5510 1585);
FORCEPROP 0 LASTPIN (5500 1725) $PN AC13
J 0
(5510 1735);
DISPLAY 0.680851 (5510 1735);
PAINT MONO (5510 1735);
FORCEPROP 0 LASTPIN (5500 1775) $PN AC21
J 0
(5510 1785);
DISPLAY 0.680851 (5510 1785);
PAINT MONO (5510 1785);
FORCEPROP 0 LASTPIN (5500 1825) $PN AC27
J 0
(5510 1835);
DISPLAY 0.680851 (5510 1835);
PAINT MONO (5510 1835);
FORCEPROP 0 LASTPIN (5500 1875) $PN AC33
J 0
(5510 1885);
DISPLAY 0.680851 (5510 1885);
PAINT MONO (5510 1885);
FORCEPROP 0 LASTPIN (5500 1925) $PN AC39
J 0
(5510 1935);
DISPLAY 0.680851 (5510 1935);
PAINT MONO (5510 1935);
FORCEPROP 0 LASTPIN (5500 1975) $PN AC45
J 0
(5510 1985);
DISPLAY 0.680851 (5510 1985);
PAINT MONO (5510 1985);
FORCEPROP 0 LASTPIN (5500 1625) $PN AC5
J 0
(5510 1635);
DISPLAY 0.680851 (5510 1635);
PAINT MONO (5510 1635);
FORCEPROP 0 LASTPIN (5500 2025) $PN AC52
J 0
(5510 2035);
DISPLAY 0.680851 (5510 2035);
PAINT MONO (5510 2035);
FORCEPROP 0 LASTPIN (5500 2075) $PN AC58
J 0
(5510 2085);
DISPLAY 0.680851 (5510 2085);
PAINT MONO (5510 2085);
FORCEPROP 0 LASTPIN (5500 2125) $PN AC64
J 0
(5510 2135);
DISPLAY 0.680851 (5510 2135);
PAINT MONO (5510 2135);
FORCEPROP 0 LASTPIN (5500 2175) $PN AC70
J 0
(5510 2185);
DISPLAY 0.680851 (5510 2185);
PAINT MONO (5510 2185);
FORCEPROP 0 LASTPIN (5500 2225) $PN AC76
J 0
(5510 2235);
DISPLAY 0.680851 (5510 2235);
PAINT MONO (5510 2235);
FORCEPROP 0 LASTPIN (5500 2275) $PN AC84
J 0
(5510 2285);
DISPLAY 0.680851 (5510 2285);
PAINT MONO (5510 2285);
FORCEPROP 0 LASTPIN (5500 2325) $PN AC88
J 0
(5510 2335);
DISPLAY 0.680851 (5510 2335);
PAINT MONO (5510 2335);
FORCEPROP 0 LASTPIN (5500 1675) $PN AC9
J 0
(5510 1685);
DISPLAY 0.680851 (5510 1685);
PAINT MONO (5510 1685);
FORCEPROP 0 LASTPIN (5500 2475) $PN AD12
J 0
(5510 2485);
DISPLAY 0.680851 (5510 2485);
PAINT MONO (5510 2485);
FORCEPROP 0 LASTPIN (5500 2525) $PN AD16
J 0
(5510 2535);
DISPLAY 0.680851 (5510 2535);
PAINT MONO (5510 2535);
FORCEPROP 0 LASTPIN (5500 2375) $PN AD4
J 0
(5510 2385);
DISPLAY 0.680851 (5510 2385);
PAINT MONO (5510 2385);
FORCEPROP 0 LASTPIN (5500 2575) $PN AD42
J 0
(5510 2585);
DISPLAY 0.680851 (5510 2585);
PAINT MONO (5510 2585);
FORCEPROP 0 LASTPIN (5500 2625) $PN AD79
J 0
(5510 2635);
DISPLAY 0.680851 (5510 2635);
PAINT MONO (5510 2635);
FORCEPROP 0 LASTPIN (5500 2425) $PN AD8
J 0
(5510 2435);
DISPLAY 0.680851 (5510 2435);
PAINT MONO (5510 2435);
FORCEPROP 0 LASTPIN (5500 2675) $PN AD83
J 0
(5510 2685);
DISPLAY 0.680851 (5510 2685);
PAINT MONO (5510 2685);
FORCEPROP 0 LASTPIN (5500 2725) $PN AE17
J 0
(5510 2735);
DISPLAY 0.680851 (5510 2735);
PAINT MONO (5510 2735);
FORCEPROP 0 LASTPIN (5500 2775) $PN AE19
J 0
(5510 2785);
DISPLAY 0.680851 (5510 2785);
PAINT MONO (5510 2785);
FORCEPROP 0 LASTPIN (5500 2825) $PN AE21
J 0
(5510 2835);
DISPLAY 0.680851 (5510 2835);
PAINT MONO (5510 2835);
FORCEPROP 0 LASTPIN (5500 2875) $PN AE23
J 0
(5510 2885);
DISPLAY 0.680851 (5510 2885);
PAINT MONO (5510 2885);
FORCEPROP 0 LASTPIN (5500 2925) $PN AE25
J 0
(5510 2935);
DISPLAY 0.680851 (5510 2935);
PAINT MONO (5510 2935);
FORCEPROP 0 LASTPIN (5500 2975) $PN AE27
J 0
(5510 2985);
DISPLAY 0.680851 (5510 2985);
PAINT MONO (5510 2985);
FORCEPROP 0 LASTPIN (5500 3025) $PN AE29
J 0
(5510 3035);
DISPLAY 0.680851 (5510 3035);
PAINT MONO (5510 3035);
FORCEPROP 0 LASTPIN (5500 3075) $PN AE31
J 0
(5510 3085);
DISPLAY 0.680851 (5510 3085);
PAINT MONO (5510 3085);
FORCEPROP 0 LASTPIN (5500 3125) $PN AE33
J 0
(5510 3135);
DISPLAY 0.680851 (5510 3135);
PAINT MONO (5510 3135);
FORCEPROP 0 LASTPIN (5500 3175) $PN AE35
J 0
(5510 3185);
DISPLAY 0.680851 (5510 3185);
PAINT MONO (5510 3185);
FORCEPROP 0 LASTPIN (5500 3225) $PN AE37
J 0
(5510 3235);
DISPLAY 0.680851 (5510 3235);
PAINT MONO (5510 3235);
FORCEPROP 0 LASTPIN (5500 3275) $PN AE39
J 0
(5510 3285);
DISPLAY 0.680851 (5510 3285);
PAINT MONO (5510 3285);
FORCEPROP 0 LASTPIN (5500 3325) $PN AE41
J 0
(5510 3335);
DISPLAY 0.680851 (5510 3335);
PAINT MONO (5510 3335);
FORCEPROP 0 LASTPIN (5500 3375) $PN AE43
J 0
(5510 3385);
DISPLAY 0.680851 (5510 3385);
PAINT MONO (5510 3385);
FORCEPROP 0 LASTPIN (5500 3425) $PN AE45
J 0
(5510 3435);
DISPLAY 0.680851 (5510 3435);
PAINT MONO (5510 3435);
FORCEPROP 0 LASTPIN (5500 3475) $PN AE48
J 0
(5510 3485);
DISPLAY 0.680851 (5510 3485);
PAINT MONO (5510 3485);
FORCEPROP 0 LASTPIN (5500 3525) $PN AE50
J 0
(5510 3535);
DISPLAY 0.680851 (5510 3535);
PAINT MONO (5510 3535);
FORCEPROP 0 LASTPIN (5500 3575) $PN AE52
J 0
(5510 3585);
DISPLAY 0.680851 (5510 3585);
PAINT MONO (5510 3585);
FORCEPROP 0 LASTPIN (5500 3625) $PN AE54
J 0
(5510 3635);
DISPLAY 0.680851 (5510 3635);
PAINT MONO (5510 3635);
FORCEPROP 0 LASTPIN (5500 3675) $PN AE56
J 0
(5510 3685);
DISPLAY 0.680851 (5510 3685);
PAINT MONO (5510 3685);
FORCEPROP 0 LASTPIN (5500 3725) $PN AE58
J 0
(5510 3735);
DISPLAY 0.680851 (5510 3735);
PAINT MONO (5510 3735);
FORCEPROP 0 LASTPIN (5500 3775) $PN AE60
J 0
(5510 3785);
DISPLAY 0.680851 (5510 3785);
PAINT MONO (5510 3785);
FORCEPROP 0 LASTPIN (5500 3825) $PN AE62
J 0
(5510 3835);
DISPLAY 0.680851 (5510 3835);
PAINT MONO (5510 3835);
FORCEPROP 0 LASTPIN (5500 3875) $PN AE64
J 0
(5510 3885);
DISPLAY 0.680851 (5510 3885);
PAINT MONO (5510 3885);
FORCEPROP 0 LASTPIN (5500 3925) $PN AE66
J 0
(5510 3935);
DISPLAY 0.680851 (5510 3935);
PAINT MONO (5510 3935);
FORCEPROP 0 LASTPIN (3100 -25) $PN AE68
J 2
(3090 -15);
DISPLAY 0.680851 (3090 -15);
PAINT MONO (3090 -15);
FORCEPROP 0 LASTPIN (3100 25) $PN AE70
J 2
(3090 35);
DISPLAY 0.680851 (3090 35);
PAINT MONO (3090 35);
FORCEPROP 0 LASTPIN (3100 75) $PN AE72
J 2
(3090 85);
DISPLAY 0.680851 (3090 85);
PAINT MONO (3090 85);
FORCEPROP 0 LASTPIN (3100 125) $PN AE74
J 2
(3090 135);
DISPLAY 0.680851 (3090 135);
PAINT MONO (3090 135);
FORCEPROP 0 LASTPIN (3100 175) $PN AE76
J 2
(3090 185);
DISPLAY 0.680851 (3090 185);
PAINT MONO (3090 185);
FORCEPROP 0 LASTPIN (3100 225) $PN AE78
J 2
(3090 235);
DISPLAY 0.680851 (3090 235);
PAINT MONO (3090 235);
FORCEPROP 0 LASTPIN (3100 275) $PN AE84
J 2
(3090 285);
DISPLAY 0.680851 (3090 285);
PAINT MONO (3090 285);
FORCEPROP 0 LASTPIN (3100 325) $PN AE88
J 2
(3090 335);
DISPLAY 0.680851 (3090 335);
PAINT MONO (3090 335);
FORCEPROP 0 LASTPIN (3100 475) $PN AF12
J 2
(3090 485);
DISPLAY 0.680851 (3090 485);
PAINT MONO (3090 485);
FORCEPROP 0 LASTPIN (3100 525) $PN AF16
J 2
(3090 535);
DISPLAY 0.680851 (3090 535);
PAINT MONO (3090 535);
FORCEPROP 0 LASTPIN (3100 375) $PN AF4
J 2
(3090 385);
DISPLAY 0.680851 (3090 385);
PAINT MONO (3090 385);
FORCEPROP 0 LASTPIN (3100 575) $PN AF42
J 2
(3090 585);
DISPLAY 0.680851 (3090 585);
PAINT MONO (3090 585);
FORCEPROP 0 LASTPIN (3100 425) $PN AF8
J 2
(3090 435);
DISPLAY 0.680851 (3090 435);
PAINT MONO (3090 435);
FORCEPROP 0 LASTPIN (3100 625) $PN AF81
J 2
(3090 635);
DISPLAY 0.680851 (3090 635);
PAINT MONO (3090 635);
FORCEPROP 0 LASTPIN (3100 675) $PN AF87
J 2
(3090 685);
DISPLAY 0.680851 (3090 685);
PAINT MONO (3090 685);
FORCEPROP 0 LASTPIN (3100 725) $PN AF91
J 2
(3090 735);
DISPLAY 0.680851 (3090 735);
PAINT MONO (3090 735);
FORCEPROP 0 LASTPIN (3100 775) $PN AG1
J 2
(3090 785);
DISPLAY 0.680851 (3090 785);
PAINT MONO (3090 785);
FORCEPROP 0 LASTPIN (3100 925) $PN AG13
J 2
(3090 935);
DISPLAY 0.680851 (3090 935);
PAINT MONO (3090 935);
FORCEPROP 0 LASTPIN (3100 975) $PN AG21
J 2
(3090 985);
DISPLAY 0.680851 (3090 985);
PAINT MONO (3090 985);
FORCEPROP 0 LASTPIN (3100 1025) $PN AG27
J 2
(3090 1035);
DISPLAY 0.680851 (3090 1035);
PAINT MONO (3090 1035);
FORCEPROP 0 LASTPIN (3100 1075) $PN AG33
J 2
(3090 1085);
DISPLAY 0.680851 (3090 1085);
PAINT MONO (3090 1085);
FORCEPROP 0 LASTPIN (3100 1125) $PN AG39
J 2
(3090 1135);
DISPLAY 0.680851 (3090 1135);
PAINT MONO (3090 1135);
FORCEPROP 0 LASTPIN (3100 1175) $PN AG45
J 2
(3090 1185);
DISPLAY 0.680851 (3090 1185);
PAINT MONO (3090 1185);
FORCEPROP 0 LASTPIN (3100 825) $PN AG5
J 2
(3090 835);
DISPLAY 0.680851 (3090 835);
PAINT MONO (3090 835);
FORCEPROP 0 LASTPIN (3100 1225) $PN AG52
J 2
(3090 1235);
DISPLAY 0.680851 (3090 1235);
PAINT MONO (3090 1235);
FORCEPROP 0 LASTPIN (3100 1275) $PN AG58
J 2
(3090 1285);
DISPLAY 0.680851 (3090 1285);
PAINT MONO (3090 1285);
FORCEPROP 0 LASTPIN (3100 1325) $PN AG64
J 2
(3090 1335);
DISPLAY 0.680851 (3090 1335);
PAINT MONO (3090 1335);
FORCEPROP 0 LASTPIN (3100 1375) $PN AG70
J 2
(3090 1385);
DISPLAY 0.680851 (3090 1385);
PAINT MONO (3090 1385);
FORCEPROP 0 LASTPIN (3100 1425) $PN AG76
J 2
(3090 1435);
DISPLAY 0.680851 (3090 1435);
PAINT MONO (3090 1435);
FORCEPROP 0 LASTPIN (3100 1475) $PN AG84
J 2
(3090 1485);
DISPLAY 0.680851 (3090 1485);
PAINT MONO (3090 1485);
FORCEPROP 0 LASTPIN (3100 1525) $PN AG88
J 2
(3090 1535);
DISPLAY 0.680851 (3090 1535);
PAINT MONO (3090 1535);
FORCEPROP 0 LASTPIN (3100 875) $PN AG9
J 2
(3090 885);
DISPLAY 0.680851 (3090 885);
PAINT MONO (3090 885);
FORCEPROP 0 LASTPIN (3100 1675) $PN AH12
J 2
(3090 1685);
DISPLAY 0.680851 (3090 1685);
PAINT MONO (3090 1685);
FORCEPROP 0 LASTPIN (3100 1725) $PN AH16
J 2
(3090 1735);
DISPLAY 0.680851 (3090 1735);
PAINT MONO (3090 1735);
FORCEPROP 0 LASTPIN (3100 1775) $PN AH20
J 2
(3090 1785);
DISPLAY 0.680851 (3090 1785);
PAINT MONO (3090 1785);
FORCEPROP 0 LASTPIN (3100 1825) $PN AH22
J 2
(3090 1835);
DISPLAY 0.680851 (3090 1835);
PAINT MONO (3090 1835);
FORCEPROP 0 LASTPIN (3100 1875) $PN AH26
J 2
(3090 1885);
DISPLAY 0.680851 (3090 1885);
PAINT MONO (3090 1885);
FORCEPROP 0 LASTPIN (3100 1925) $PN AH28
J 2
(3090 1935);
DISPLAY 0.680851 (3090 1935);
PAINT MONO (3090 1935);
FORCEPROP 0 LASTPIN (3100 1975) $PN AH32
J 2
(3090 1985);
DISPLAY 0.680851 (3090 1985);
PAINT MONO (3090 1985);
FORCEPROP 0 LASTPIN (3100 2025) $PN AH34
J 2
(3090 2035);
DISPLAY 0.680851 (3090 2035);
PAINT MONO (3090 2035);
FORCEPROP 0 LASTPIN (3100 2075) $PN AH38
J 2
(3090 2085);
DISPLAY 0.680851 (3090 2085);
PAINT MONO (3090 2085);
FORCEPROP 0 LASTPIN (3100 1575) $PN AH4
J 2
(3090 1585);
DISPLAY 0.680851 (3090 1585);
PAINT MONO (3090 1585);
FORCEPROP 0 LASTPIN (3100 2125) $PN AH40
J 2
(3090 2135);
DISPLAY 0.680851 (3090 2135);
PAINT MONO (3090 2135);
FORCEPROP 0 LASTPIN (3100 2175) $PN AH44
J 2
(3090 2185);
DISPLAY 0.680851 (3090 2185);
PAINT MONO (3090 2185);
FORCEPROP 0 LASTPIN (3100 2225) $PN AH47
J 2
(3090 2235);
DISPLAY 0.680851 (3090 2235);
PAINT MONO (3090 2235);
FORCEPROP 0 LASTPIN (3100 2275) $PN AH51
J 2
(3090 2285);
DISPLAY 0.680851 (3090 2285);
PAINT MONO (3090 2285);
FORCEPROP 0 LASTPIN (3100 2325) $PN AH53
J 2
(3090 2335);
DISPLAY 0.680851 (3090 2335);
PAINT MONO (3090 2335);
FORCEPROP 0 LASTPIN (3100 2375) $PN AH57
J 2
(3090 2385);
DISPLAY 0.680851 (3090 2385);
PAINT MONO (3090 2385);
FORCEPROP 0 LASTPIN (3100 2425) $PN AH59
J 2
(3090 2435);
DISPLAY 0.680851 (3090 2435);
PAINT MONO (3090 2435);
FORCEPROP 0 LASTPIN (3100 2475) $PN AH63
J 2
(3090 2485);
DISPLAY 0.680851 (3090 2485);
PAINT MONO (3090 2485);
FORCEPROP 0 LASTPIN (3100 2525) $PN AH65
J 2
(3090 2535);
DISPLAY 0.680851 (3090 2535);
PAINT MONO (3090 2535);
FORCEPROP 0 LASTPIN (3100 2575) $PN AH69
J 2
(3090 2585);
DISPLAY 0.680851 (3090 2585);
PAINT MONO (3090 2585);
FORCEPROP 0 LASTPIN (3100 2625) $PN AH71
J 2
(3090 2635);
DISPLAY 0.680851 (3090 2635);
PAINT MONO (3090 2635);
FORCEPROP 0 LASTPIN (3100 2675) $PN AH75
J 2
(3090 2685);
DISPLAY 0.680851 (3090 2685);
PAINT MONO (3090 2685);
FORCEPROP 0 LASTPIN (3100 2725) $PN AH77
J 2
(3090 2735);
DISPLAY 0.680851 (3090 2735);
PAINT MONO (3090 2735);
FORCEPROP 0 LASTPIN (3100 2775) $PN AH79
J 2
(3090 2785);
DISPLAY 0.680851 (3090 2785);
PAINT MONO (3090 2785);
FORCEPROP 0 LASTPIN (3100 1625) $PN AH8
J 2
(3090 1635);
DISPLAY 0.680851 (3090 1635);
PAINT MONO (3090 1635);
FORCEPROP 0 LASTPIN (3100 2825) $PN AH83
J 2
(3090 2835);
DISPLAY 0.680851 (3090 2835);
PAINT MONO (3090 2835);
FORCEPROP 0 LASTPIN (3100 2875) $PN AJ19
J 2
(3090 2885);
DISPLAY 0.680851 (3090 2885);
PAINT MONO (3090 2885);
FORCEPROP 0 LASTPIN (3100 2925) $PN AJ23
J 2
(3090 2935);
DISPLAY 0.680851 (3090 2935);
PAINT MONO (3090 2935);
FORCEPROP 0 LASTPIN (3100 2975) $PN AJ25
J 2
(3090 2985);
DISPLAY 0.680851 (3090 2985);
PAINT MONO (3090 2985);
FORCEPROP 0 LASTPIN (3100 3025) $PN AJ29
J 2
(3090 3035);
DISPLAY 0.680851 (3090 3035);
PAINT MONO (3090 3035);
FORCEPROP 0 LASTPIN (3100 3075) $PN AJ31
J 2
(3090 3085);
DISPLAY 0.680851 (3090 3085);
PAINT MONO (3090 3085);
FORCEPROP 0 LASTPIN (3100 3125) $PN AJ35
J 2
(3090 3135);
DISPLAY 0.680851 (3090 3135);
PAINT MONO (3090 3135);
FORCEPROP 0 LASTPIN (3100 3175) $PN AJ37
J 2
(3090 3185);
DISPLAY 0.680851 (3090 3185);
PAINT MONO (3090 3185);
FORCEPROP 0 LASTPIN (3100 3225) $PN AJ41
J 2
(3090 3235);
DISPLAY 0.680851 (3090 3235);
PAINT MONO (3090 3235);
FORCEPROP 0 LASTPIN (3100 3275) $PN AJ43
J 2
(3090 3285);
DISPLAY 0.680851 (3090 3285);
PAINT MONO (3090 3285);
FORCEPROP 0 LASTPIN (3100 3325) $PN AJ48
J 2
(3090 3335);
DISPLAY 0.680851 (3090 3335);
PAINT MONO (3090 3335);
FORCEPROP 0 LASTPIN (3100 3375) $PN AJ50
J 2
(3090 3385);
DISPLAY 0.680851 (3090 3385);
PAINT MONO (3090 3385);
FORCEPROP 0 LASTPIN (3100 3425) $PN AJ54
J 2
(3090 3435);
DISPLAY 0.680851 (3090 3435);
PAINT MONO (3090 3435);
FORCEPROP 0 LASTPIN (3100 3475) $PN AJ56
J 2
(3090 3485);
DISPLAY 0.680851 (3090 3485);
PAINT MONO (3090 3485);
FORCEPROP 0 LASTPIN (3100 3525) $PN AJ60
J 2
(3090 3535);
DISPLAY 0.680851 (3090 3535);
PAINT MONO (3090 3535);
FORCEPROP 0 LASTPIN (3100 3575) $PN AJ62
J 2
(3090 3585);
DISPLAY 0.680851 (3090 3585);
PAINT MONO (3090 3585);
FORCEPROP 0 LASTPIN (3100 3625) $PN AJ66
J 2
(3090 3635);
DISPLAY 0.680851 (3090 3635);
PAINT MONO (3090 3635);
FORCEPROP 0 LASTPIN (3100 3675) $PN AJ68
J 2
(3090 3685);
DISPLAY 0.680851 (3090 3685);
PAINT MONO (3090 3685);
FORCEPROP 0 LASTPIN (3100 3725) $PN AJ72
J 2
(3090 3735);
DISPLAY 0.680851 (3090 3735);
PAINT MONO (3090 3735);
FORCEPROP 0 LASTPIN (3100 3775) $PN AJ74
J 2
(3090 3785);
DISPLAY 0.680851 (3090 3785);
PAINT MONO (3090 3785);
FORCEPROP 0 LASTPIN (3100 3825) $PN AJ78
J 2
(3090 3835);
DISPLAY 0.680851 (3090 3835);
PAINT MONO (3090 3835);
FORCEPROP 0 LASTPIN (3100 3875) $PN AJ84
J 2
(3090 3885);
DISPLAY 0.680851 (3090 3885);
PAINT MONO (3090 3885);
FORCEPROP 0 LASTPIN (3100 3925) $PN AJ88
J 2
(3090 3935);
DISPLAY 0.680851 (3090 3935);
PAINT MONO (3090 3935);
FORCEPROP 2 LAST CDS_LIB pure_quanta
J 0
(4300 1950);
DISPLAY INVISIBLE (4300 1950);
FORCEPROP 1 LAST NEEDS_NO_SIZE TRUE
J 0
(4300 1950);
DISPLAY 0.723404 (4300 1950);
PAINT GREEN (4300 1950);
DISPLAY INVISIBLE (4300 1950);
FORCEPROP 1 LAST CDS_LMAN_SYM_OUTLINE -1050,2150,1050,-2100
J 0
(4300 1950);
DISPLAY 0.468085 (4300 1950);
PAINT GREEN (4300 1950);
DISPLAY INVISIBLE (4300 1950);
FORCEPROP 2 LAST CDS_LOCATION U2
J 0
(3250 4425);
DISPLAY 1.021277 (3250 4425);
DISPLAY INVISIBLE (3250 4425);
FORCEPROP 0 LAST $SEC 39
J 0
(3250 4425);
DISPLAY 0.680851 (3250 4425);
PAINT MONO (3250 4425);
DISPLAY INVISIBLE (3250 4425);
FORCEPROP 2 LAST CDS_SEC 39
J 0
(3250 4425);
DISPLAY 1.021277 (3250 4425);
DISPLAY INVISIBLE (3250 4425);
FORCEPROP 1 LAST PATH I11
J 0
(4300 1950);
DISPLAY 0.723404 (4300 1950);
PAINT GREEN (4300 1950);
DISPLAY INVISIBLE (4300 1950);
FORCEADD UNIVERSAL_GND..1
(-325 -575);
FORCEPROP 3 LASTPIN (-325 -525) SIG_NAME GND\g
J 0
(-315 -515);
DISPLAY 0.659574 (-315 -515);
PAINT MONO (-315 -515);
DISPLAY INVISIBLE (-315 -515);
FORCEPROP 2 LAST CDS_LIB logical_power
J 0
(-325 -575);
PAINT MONO (-325 -575);
DISPLAY INVISIBLE (-325 -575);
FORCEPROP 1 LAST HDL_POWER GND
J 1
(-300 -650);
DISPLAY 0.872340 (-300 -650);
PAINT GREEN (-300 -650);
DISPLAY INVISIBLE (-300 -650);
FORCEPROP 1 LAST PATH I3
J 0
(-250 -575);
DISPLAY 0.872340 (-250 -575);
PAINT AQUA (-250 -575);
DISPLAY INVISIBLE (-250 -575);
FORCEADD UNIVERSAL_GND..1
(-175 -575);
FORCEPROP 3 LASTPIN (-175 -525) SIG_NAME GND\g
J 0
(-165 -515);
DISPLAY 0.659574 (-165 -515);
PAINT MONO (-165 -515);
DISPLAY INVISIBLE (-165 -515);
FORCEPROP 2 LAST CDS_LIB logical_power
J 0
(-175 -575);
PAINT MONO (-175 -575);
DISPLAY INVISIBLE (-175 -575);
FORCEPROP 1 LAST HDL_POWER GND
J 1
(-150 -650);
DISPLAY 0.872340 (-150 -650);
PAINT GREEN (-150 -650);
DISPLAY INVISIBLE (-150 -650);
FORCEPROP 1 LAST PATH I4
J 0
(-100 -575);
DISPLAY 0.872340 (-100 -575);
PAINT AQUA (-100 -575);
DISPLAY INVISIBLE (-100 -575);
FORCEADD UNIVERSAL_GND..1
(2725 -575);
FORCEPROP 3 LASTPIN (2725 -525) SIG_NAME GND\g
J 0
(2735 -515);
DISPLAY 0.659574 (2735 -515);
PAINT MONO (2735 -515);
DISPLAY INVISIBLE (2735 -515);
FORCEPROP 2 LAST CDS_LIB logical_power
J 0
(2725 -575);
PAINT MONO (2725 -575);
DISPLAY INVISIBLE (2725 -575);
FORCEPROP 1 LAST HDL_POWER GND
J 1
(2750 -650);
DISPLAY 0.872340 (2750 -650);
PAINT GREEN (2750 -650);
DISPLAY INVISIBLE (2750 -650);
FORCEPROP 1 LAST PATH I5
J 0
(2800 -575);
DISPLAY 0.872340 (2800 -575);
PAINT AQUA (2800 -575);
DISPLAY INVISIBLE (2800 -575);
FORCEADD UNIVERSAL_GND..1
(2850 -575);
FORCEPROP 3 LASTPIN (2850 -525) SIG_NAME GND\g
J 0
(2860 -515);
DISPLAY 0.659574 (2860 -515);
PAINT MONO (2860 -515);
DISPLAY INVISIBLE (2860 -515);
FORCEPROP 2 LAST CDS_LIB logical_power
J 0
(2850 -575);
PAINT MONO (2850 -575);
DISPLAY INVISIBLE (2850 -575);
FORCEPROP 1 LAST HDL_POWER GND
J 1
(2875 -650);
DISPLAY 0.872340 (2875 -650);
PAINT GREEN (2875 -650);
DISPLAY INVISIBLE (2875 -650);
FORCEPROP 1 LAST PATH I6
J 0
(2925 -575);
DISPLAY 0.872340 (2925 -575);
PAINT AQUA (2925 -575);
DISPLAY INVISIBLE (2925 -575);
FORCEADD UNIVERSAL_GND..1
(5750 -575);
FORCEPROP 3 LASTPIN (5750 -525) SIG_NAME GND\g
J 0
(5760 -515);
DISPLAY 0.659574 (5760 -515);
PAINT MONO (5760 -515);
DISPLAY INVISIBLE (5760 -515);
FORCEPROP 2 LAST CDS_LIB logical_power
J 0
(5750 -575);
PAINT MONO (5750 -575);
DISPLAY INVISIBLE (5750 -575);
FORCEPROP 1 LAST HDL_POWER GND
J 1
(5775 -650);
DISPLAY 0.872340 (5775 -650);
PAINT GREEN (5775 -650);
DISPLAY INVISIBLE (5775 -650);
FORCEPROP 1 LAST PATH I8
J 0
(5825 -575);
DISPLAY 0.872340 (5825 -575);
PAINT AQUA (5825 -575);
DISPLAY INVISIBLE (5825 -575);
FORCEADD SOCKET4677_AZIF0045P001C01CS..37
(-1775 1950);
FORCEPROP 1 LAST PART_NUMBER DGA^7000023
J 0
(-2825 4200);
DISPLAY 0.723404 (-2825 4200);
PAINT GREEN (-2825 4200);
DISPLAY INVISIBLE (-2825 4200);
FORCEPROP 2 LAST PART_TYPE SMLF
J 0
(-2825 4375);
DISPLAY 1.021277 (-2825 4375);
FORCEPROP 1 LAST MATERIAL IO
J 0
(-2825 4125);
DISPLAY 0.723404 (-2825 4125);
PAINT GREEN (-2825 4125);
FORCEPROP 2 LAST VALUE SOCKET4677_AZIF0045-P001C01CS
J 0
(-2825 4325);
DISPLAY 1.021277 (-2825 4325);
FORCEPROP 1 LAST $LOCATION U2
J 0
(-2825 4275);
DISPLAY 0.723404 (-2825 4275);
PAINT GREEN (-2825 4275);
FORCEPROP 0 LASTPIN (-2975 3575) $PN BR5
J 2
(-2985 3585);
DISPLAY 0.680851 (-2985 3585);
PAINT MONO (-2985 3585);
FORCEPROP 0 LASTPIN (-575 -25) $PN AW21
J 0
(-565 -15);
DISPLAY 0.680851 (-565 -15);
PAINT MONO (-565 -15);
FORCEPROP 0 LASTPIN (-575 25) $PN AW23
J 0
(-565 35);
DISPLAY 0.680851 (-565 35);
PAINT MONO (-565 35);
FORCEPROP 0 LASTPIN (-575 75) $PN AW25
J 0
(-565 85);
DISPLAY 0.680851 (-565 85);
PAINT MONO (-565 85);
FORCEPROP 0 LASTPIN (-575 125) $PN AW62
J 0
(-565 135);
DISPLAY 0.680851 (-565 135);
PAINT MONO (-565 135);
FORCEPROP 0 LASTPIN (-575 175) $PN AW66
J 0
(-565 185);
DISPLAY 0.680851 (-565 185);
PAINT MONO (-565 185);
FORCEPROP 0 LASTPIN (-575 225) $PN AW68
J 0
(-565 235);
DISPLAY 0.680851 (-565 235);
PAINT MONO (-565 235);
FORCEPROP 0 LASTPIN (-575 275) $PN AW72
J 0
(-565 285);
DISPLAY 0.680851 (-565 285);
PAINT MONO (-565 285);
FORCEPROP 0 LASTPIN (-575 325) $PN AW80
J 0
(-565 335);
DISPLAY 0.680851 (-565 335);
PAINT MONO (-565 335);
FORCEPROP 0 LASTPIN (-575 375) $PN AW82
J 0
(-565 385);
DISPLAY 0.680851 (-565 385);
PAINT MONO (-565 385);
FORCEPROP 0 LASTPIN (-575 425) $PN AW84
J 0
(-565 435);
DISPLAY 0.680851 (-565 435);
PAINT MONO (-565 435);
FORCEPROP 0 LASTPIN (-575 475) $PN AW88
J 0
(-565 485);
DISPLAY 0.680851 (-565 485);
PAINT MONO (-565 485);
FORCEPROP 0 LASTPIN (-575 625) $PN AY12
J 0
(-565 635);
DISPLAY 0.680851 (-565 635);
PAINT MONO (-565 635);
FORCEPROP 0 LASTPIN (-575 675) $PN AY16
J 0
(-565 685);
DISPLAY 0.680851 (-565 685);
PAINT MONO (-565 685);
FORCEPROP 0 LASTPIN (-575 525) $PN AY4
J 0
(-565 535);
DISPLAY 0.680851 (-565 535);
PAINT MONO (-565 535);
FORCEPROP 0 LASTPIN (-575 725) $PN AY71
J 0
(-565 735);
DISPLAY 0.680851 (-565 735);
PAINT MONO (-565 735);
FORCEPROP 0 LASTPIN (-575 775) $PN AY77
J 0
(-565 785);
DISPLAY 0.680851 (-565 785);
PAINT MONO (-565 785);
FORCEPROP 0 LASTPIN (-575 825) $PN AY79
J 0
(-565 835);
DISPLAY 0.680851 (-565 835);
PAINT MONO (-565 835);
FORCEPROP 0 LASTPIN (-575 575) $PN AY8
J 0
(-565 585);
DISPLAY 0.680851 (-565 585);
PAINT MONO (-565 585);
FORCEPROP 0 LASTPIN (-575 875) $PN AY81
J 0
(-565 885);
DISPLAY 0.680851 (-565 885);
PAINT MONO (-565 885);
FORCEPROP 0 LASTPIN (-575 925) $PN AY83
J 0
(-565 935);
DISPLAY 0.680851 (-565 935);
PAINT MONO (-565 935);
FORCEPROP 0 LASTPIN (-575 975) $PN BA17
J 0
(-565 985);
DISPLAY 0.680851 (-565 985);
PAINT MONO (-565 985);
FORCEPROP 0 LASTPIN (-575 1025) $PN BA60
J 0
(-565 1035);
DISPLAY 0.680851 (-565 1035);
PAINT MONO (-565 1035);
FORCEPROP 0 LASTPIN (-575 1075) $PN BA64
J 0
(-565 1085);
DISPLAY 0.680851 (-565 1085);
PAINT MONO (-565 1085);
FORCEPROP 0 LASTPIN (-575 1125) $PN BA74
J 0
(-565 1135);
DISPLAY 0.680851 (-565 1135);
PAINT MONO (-565 1135);
FORCEPROP 0 LASTPIN (-575 1175) $PN BA84
J 0
(-565 1185);
DISPLAY 0.680851 (-565 1185);
PAINT MONO (-565 1185);
FORCEPROP 0 LASTPIN (-575 1225) $PN BA88
J 0
(-565 1235);
DISPLAY 0.680851 (-565 1235);
PAINT MONO (-565 1235);
FORCEPROP 0 LASTPIN (-575 1375) $PN BB10
J 0
(-565 1385);
DISPLAY 0.680851 (-565 1385);
PAINT MONO (-565 1385);
FORCEPROP 0 LASTPIN (-575 1425) $PN BB12
J 0
(-565 1435);
DISPLAY 0.680851 (-565 1435);
PAINT MONO (-565 1435);
FORCEPROP 0 LASTPIN (-575 1475) $PN BB16
J 0
(-565 1485);
DISPLAY 0.680851 (-565 1485);
PAINT MONO (-565 1485);
FORCEPROP 0 LASTPIN (-575 1525) $PN BB20
J 0
(-565 1535);
DISPLAY 0.680851 (-565 1535);
PAINT MONO (-565 1535);
FORCEPROP 0 LASTPIN (-575 1575) $PN BB22
J 0
(-565 1585);
DISPLAY 0.680851 (-565 1585);
PAINT MONO (-565 1585);
FORCEPROP 0 LASTPIN (-575 1625) $PN BB24
J 0
(-565 1635);
DISPLAY 0.680851 (-565 1635);
PAINT MONO (-565 1635);
FORCEPROP 0 LASTPIN (-575 1675) $PN BB26
J 0
(-565 1685);
DISPLAY 0.680851 (-565 1685);
PAINT MONO (-565 1685);
FORCEPROP 0 LASTPIN (-575 1275) $PN BB4
J 0
(-565 1285);
DISPLAY 0.680851 (-565 1285);
PAINT MONO (-565 1285);
FORCEPROP 0 LASTPIN (-575 1725) $PN BB63
J 0
(-565 1735);
DISPLAY 0.680851 (-565 1735);
PAINT MONO (-565 1735);
FORCEPROP 0 LASTPIN (-575 1775) $PN BB69
J 0
(-565 1785);
DISPLAY 0.680851 (-565 1785);
PAINT MONO (-565 1785);
FORCEPROP 0 LASTPIN (-575 1825) $PN BB71
J 0
(-565 1835);
DISPLAY 0.680851 (-565 1835);
PAINT MONO (-565 1835);
FORCEPROP 0 LASTPIN (-575 1875) $PN BB77
J 0
(-565 1885);
DISPLAY 0.680851 (-565 1885);
PAINT MONO (-565 1885);
FORCEPROP 0 LASTPIN (-575 1925) $PN BB79
J 0
(-565 1935);
DISPLAY 0.680851 (-565 1935);
PAINT MONO (-565 1935);
FORCEPROP 0 LASTPIN (-575 1325) $PN BB8
J 0
(-565 1335);
DISPLAY 0.680851 (-565 1335);
PAINT MONO (-565 1335);
FORCEPROP 0 LASTPIN (-575 1975) $PN BB83
J 0
(-565 1985);
DISPLAY 0.680851 (-565 1985);
PAINT MONO (-565 1985);
FORCEPROP 0 LASTPIN (-575 2025) $PN BB87
J 0
(-565 2035);
DISPLAY 0.680851 (-565 2035);
PAINT MONO (-565 2035);
FORCEPROP 0 LASTPIN (-575 2075) $PN BB91
J 0
(-565 2085);
DISPLAY 0.680851 (-565 2085);
PAINT MONO (-565 2085);
FORCEPROP 0 LASTPIN (-575 2125) $PN BC1
J 0
(-565 2135);
DISPLAY 0.680851 (-565 2135);
PAINT MONO (-565 2135);
FORCEPROP 0 LASTPIN (-575 2275) $PN BC13
J 0
(-565 2285);
DISPLAY 0.680851 (-565 2285);
PAINT MONO (-565 2285);
FORCEPROP 0 LASTPIN (-575 2325) $PN BC17
J 0
(-565 2335);
DISPLAY 0.680851 (-565 2335);
PAINT MONO (-565 2335);
FORCEPROP 0 LASTPIN (-575 2175) $PN BC5
J 0
(-565 2185);
DISPLAY 0.680851 (-565 2185);
PAINT MONO (-565 2185);
FORCEPROP 0 LASTPIN (-575 2375) $PN BC62
J 0
(-565 2385);
DISPLAY 0.680851 (-565 2385);
PAINT MONO (-565 2385);
FORCEPROP 0 LASTPIN (-575 2425) $PN BC66
J 0
(-565 2435);
DISPLAY 0.680851 (-565 2435);
PAINT MONO (-565 2435);
FORCEPROP 0 LASTPIN (-575 2475) $PN BC72
J 0
(-565 2485);
DISPLAY 0.680851 (-565 2485);
PAINT MONO (-565 2485);
FORCEPROP 0 LASTPIN (-575 2525) $PN BC76
J 0
(-565 2535);
DISPLAY 0.680851 (-565 2535);
PAINT MONO (-565 2535);
FORCEPROP 0 LASTPIN (-575 2575) $PN BC78
J 0
(-565 2585);
DISPLAY 0.680851 (-565 2585);
PAINT MONO (-565 2585);
FORCEPROP 0 LASTPIN (-575 2625) $PN BC84
J 0
(-565 2635);
DISPLAY 0.680851 (-565 2635);
PAINT MONO (-565 2635);
FORCEPROP 0 LASTPIN (-575 2675) $PN BC86
J 0
(-565 2685);
DISPLAY 0.680851 (-565 2685);
PAINT MONO (-565 2685);
FORCEPROP 0 LASTPIN (-575 2725) $PN BC88
J 0
(-565 2735);
DISPLAY 0.680851 (-565 2735);
PAINT MONO (-565 2735);
FORCEPROP 0 LASTPIN (-575 2225) $PN BC9
J 0
(-565 2235);
DISPLAY 0.680851 (-565 2235);
PAINT MONO (-565 2235);
FORCEPROP 0 LASTPIN (-575 2875) $PN BD12
J 0
(-565 2885);
DISPLAY 0.680851 (-565 2885);
PAINT MONO (-565 2885);
FORCEPROP 0 LASTPIN (-575 2925) $PN BD16
J 0
(-565 2935);
DISPLAY 0.680851 (-565 2935);
PAINT MONO (-565 2935);
FORCEPROP 0 LASTPIN (-575 2975) $PN BD20
J 0
(-565 2985);
DISPLAY 0.680851 (-565 2985);
PAINT MONO (-565 2985);
FORCEPROP 0 LASTPIN (-575 2775) $PN BD4
J 0
(-565 2785);
DISPLAY 0.680851 (-565 2785);
PAINT MONO (-565 2785);
FORCEPROP 0 LASTPIN (-575 2825) $PN BD8
J 0
(-565 2835);
DISPLAY 0.680851 (-565 2835);
PAINT MONO (-565 2835);
FORCEPROP 0 LASTPIN (-575 3025) $PN BD81
J 0
(-565 3035);
DISPLAY 0.680851 (-565 3035);
PAINT MONO (-565 3035);
FORCEPROP 0 LASTPIN (-575 3075) $PN BD85
J 0
(-565 3085);
DISPLAY 0.680851 (-565 3085);
PAINT MONO (-565 3085);
FORCEPROP 0 LASTPIN (-575 3125) $PN BD89
J 0
(-565 3135);
DISPLAY 0.680851 (-565 3135);
PAINT MONO (-565 3135);
FORCEPROP 0 LASTPIN (-575 3175) $PN BE64
J 0
(-565 3185);
DISPLAY 0.680851 (-565 3185);
PAINT MONO (-565 3185);
FORCEPROP 0 LASTPIN (-575 3225) $PN BE66
J 0
(-565 3235);
DISPLAY 0.680851 (-565 3235);
PAINT MONO (-565 3235);
FORCEPROP 0 LASTPIN (-575 3275) $PN BE68
J 0
(-565 3285);
DISPLAY 0.680851 (-565 3285);
PAINT MONO (-565 3285);
FORCEPROP 0 LASTPIN (-575 3325) $PN BE74
J 0
(-565 3335);
DISPLAY 0.680851 (-565 3335);
PAINT MONO (-565 3335);
FORCEPROP 0 LASTPIN (-575 3375) $PN BE76
J 0
(-565 3385);
DISPLAY 0.680851 (-565 3385);
PAINT MONO (-565 3385);
FORCEPROP 0 LASTPIN (-575 3425) $PN BE78
J 0
(-565 3435);
DISPLAY 0.680851 (-565 3435);
PAINT MONO (-565 3435);
FORCEPROP 0 LASTPIN (-575 3475) $PN BE84
J 0
(-565 3485);
DISPLAY 0.680851 (-565 3485);
PAINT MONO (-565 3485);
FORCEPROP 0 LASTPIN (-575 3625) $PN BF12
J 0
(-565 3635);
DISPLAY 0.680851 (-565 3635);
PAINT MONO (-565 3635);
FORCEPROP 0 LASTPIN (-575 3675) $PN BF16
J 0
(-565 3685);
DISPLAY 0.680851 (-565 3685);
PAINT MONO (-565 3685);
FORCEPROP 0 LASTPIN (-575 3725) $PN BF20
J 0
(-565 3735);
DISPLAY 0.680851 (-565 3735);
PAINT MONO (-565 3735);
FORCEPROP 0 LASTPIN (-575 3525) $PN BF4
J 0
(-565 3535);
DISPLAY 0.680851 (-565 3535);
PAINT MONO (-565 3535);
FORCEPROP 0 LASTPIN (-575 3775) $PN BF61
J 0
(-565 3785);
DISPLAY 0.680851 (-565 3785);
PAINT MONO (-565 3785);
FORCEPROP 0 LASTPIN (-575 3825) $PN BF63
J 0
(-565 3835);
DISPLAY 0.680851 (-565 3835);
PAINT MONO (-565 3835);
FORCEPROP 0 LASTPIN (-575 3875) $PN BF73
J 0
(-565 3885);
DISPLAY 0.680851 (-565 3885);
PAINT MONO (-565 3885);
FORCEPROP 0 LASTPIN (-575 3925) $PN BF75
J 0
(-565 3935);
DISPLAY 0.680851 (-565 3935);
PAINT MONO (-565 3935);
FORCEPROP 0 LASTPIN (-2975 -25) $PN BF79
J 2
(-2985 -15);
DISPLAY 0.680851 (-2985 -15);
PAINT MONO (-2985 -15);
FORCEPROP 0 LASTPIN (-575 3575) $PN BF8
J 0
(-565 3585);
DISPLAY 0.680851 (-565 3585);
PAINT MONO (-565 3585);
FORCEPROP 0 LASTPIN (-2975 25) $PN BF83
J 2
(-2985 35);
DISPLAY 0.680851 (-2985 35);
PAINT MONO (-2985 35);
FORCEPROP 0 LASTPIN (-2975 75) $PN BG1
J 2
(-2985 85);
DISPLAY 0.680851 (-2985 85);
PAINT MONO (-2985 85);
FORCEPROP 0 LASTPIN (-2975 225) $PN BG13
J 2
(-2985 235);
DISPLAY 0.680851 (-2985 235);
PAINT MONO (-2985 235);
FORCEPROP 0 LASTPIN (-2975 275) $PN BG17
J 2
(-2985 285);
DISPLAY 0.680851 (-2985 285);
PAINT MONO (-2985 285);
FORCEPROP 0 LASTPIN (-2975 325) $PN BG21
J 2
(-2985 335);
DISPLAY 0.680851 (-2985 335);
PAINT MONO (-2985 335);
FORCEPROP 0 LASTPIN (-2975 375) $PN BG23
J 2
(-2985 385);
DISPLAY 0.680851 (-2985 385);
PAINT MONO (-2985 385);
FORCEPROP 0 LASTPIN (-2975 425) $PN BG25
J 2
(-2985 435);
DISPLAY 0.680851 (-2985 435);
PAINT MONO (-2985 435);
FORCEPROP 0 LASTPIN (-2975 125) $PN BG5
J 2
(-2985 135);
DISPLAY 0.680851 (-2985 135);
PAINT MONO (-2985 135);
FORCEPROP 0 LASTPIN (-2975 475) $PN BG70
J 2
(-2985 485);
DISPLAY 0.680851 (-2985 485);
PAINT MONO (-2985 485);
FORCEPROP 0 LASTPIN (-2975 175) $PN BG9
J 2
(-2985 185);
DISPLAY 0.680851 (-2985 185);
PAINT MONO (-2985 185);
FORCEPROP 0 LASTPIN (-2975 625) $PN BH12
J 2
(-2985 635);
DISPLAY 0.680851 (-2985 635);
PAINT MONO (-2985 635);
FORCEPROP 0 LASTPIN (-2975 675) $PN BH16
J 2
(-2985 685);
DISPLAY 0.680851 (-2985 685);
PAINT MONO (-2985 685);
FORCEPROP 0 LASTPIN (-2975 725) $PN BH20
J 2
(-2985 735);
DISPLAY 0.680851 (-2985 735);
PAINT MONO (-2985 735);
FORCEPROP 0 LASTPIN (-2975 525) $PN BH4
J 2
(-2985 535);
DISPLAY 0.680851 (-2985 535);
PAINT MONO (-2985 535);
FORCEPROP 0 LASTPIN (-2975 775) $PN BH67
J 2
(-2985 785);
DISPLAY 0.680851 (-2985 785);
PAINT MONO (-2985 785);
FORCEPROP 0 LASTPIN (-2975 825) $PN BH73
J 2
(-2985 835);
DISPLAY 0.680851 (-2985 835);
PAINT MONO (-2985 835);
FORCEPROP 0 LASTPIN (-2975 875) $PN BH77
J 2
(-2985 885);
DISPLAY 0.680851 (-2985 885);
PAINT MONO (-2985 885);
FORCEPROP 0 LASTPIN (-2975 575) $PN BH8
J 2
(-2985 585);
DISPLAY 0.680851 (-2985 585);
PAINT MONO (-2985 585);
FORCEPROP 0 LASTPIN (-2975 925) $PN BH81
J 2
(-2985 935);
DISPLAY 0.680851 (-2985 935);
PAINT MONO (-2985 935);
FORCEPROP 0 LASTPIN (-2975 975) $PN BH83
J 2
(-2985 985);
DISPLAY 0.680851 (-2985 985);
PAINT MONO (-2985 985);
FORCEPROP 0 LASTPIN (-2975 1025) $PN BJ62
J 2
(-2985 1035);
DISPLAY 0.680851 (-2985 1035);
PAINT MONO (-2985 1035);
FORCEPROP 0 LASTPIN (-2975 1075) $PN BJ68
J 2
(-2985 1085);
DISPLAY 0.680851 (-2985 1085);
PAINT MONO (-2985 1085);
FORCEPROP 0 LASTPIN (-2975 1125) $PN BJ80
J 2
(-2985 1135);
DISPLAY 0.680851 (-2985 1135);
PAINT MONO (-2985 1135);
FORCEPROP 0 LASTPIN (-2975 1175) $PN BJ82
J 2
(-2985 1185);
DISPLAY 0.680851 (-2985 1185);
PAINT MONO (-2985 1185);
FORCEPROP 0 LASTPIN (-2975 1225) $PN BJ84
J 2
(-2985 1235);
DISPLAY 0.680851 (-2985 1235);
PAINT MONO (-2985 1235);
FORCEPROP 0 LASTPIN (-2975 1275) $PN BJ86
J 2
(-2985 1285);
DISPLAY 0.680851 (-2985 1285);
PAINT MONO (-2985 1285);
FORCEPROP 0 LASTPIN (-2975 1325) $PN BJ88
J 2
(-2985 1335);
DISPLAY 0.680851 (-2985 1335);
PAINT MONO (-2985 1335);
FORCEPROP 0 LASTPIN (-2975 1375) $PN BJ90
J 2
(-2985 1385);
DISPLAY 0.680851 (-2985 1385);
PAINT MONO (-2985 1385);
FORCEPROP 0 LASTPIN (-2975 1525) $PN BK12
J 2
(-2985 1535);
DISPLAY 0.680851 (-2985 1535);
PAINT MONO (-2985 1535);
FORCEPROP 0 LASTPIN (-2975 1575) $PN BK16
J 2
(-2985 1585);
DISPLAY 0.680851 (-2985 1585);
PAINT MONO (-2985 1585);
FORCEPROP 0 LASTPIN (-2975 1625) $PN BK20
J 2
(-2985 1635);
DISPLAY 0.680851 (-2985 1635);
PAINT MONO (-2985 1635);
FORCEPROP 0 LASTPIN (-2975 1425) $PN BK4
J 2
(-2985 1435);
DISPLAY 0.680851 (-2985 1435);
PAINT MONO (-2985 1435);
FORCEPROP 0 LASTPIN (-2975 1675) $PN BK65
J 2
(-2985 1685);
DISPLAY 0.680851 (-2985 1685);
PAINT MONO (-2985 1685);
FORCEPROP 0 LASTPIN (-2975 1725) $PN BK71
J 2
(-2985 1735);
DISPLAY 0.680851 (-2985 1735);
PAINT MONO (-2985 1735);
FORCEPROP 0 LASTPIN (-2975 1775) $PN BK75
J 2
(-2985 1785);
DISPLAY 0.680851 (-2985 1785);
PAINT MONO (-2985 1785);
FORCEPROP 0 LASTPIN (-2975 1825) $PN BK79
J 2
(-2985 1835);
DISPLAY 0.680851 (-2985 1835);
PAINT MONO (-2985 1835);
FORCEPROP 0 LASTPIN (-2975 1475) $PN BK8
J 2
(-2985 1485);
DISPLAY 0.680851 (-2985 1485);
PAINT MONO (-2985 1485);
FORCEPROP 0 LASTPIN (-2975 1875) $PN BL1
J 2
(-2985 1885);
DISPLAY 0.680851 (-2985 1885);
PAINT MONO (-2985 1885);
FORCEPROP 0 LASTPIN (-2975 2025) $PN BL13
J 2
(-2985 2035);
DISPLAY 0.680851 (-2985 2035);
PAINT MONO (-2985 2035);
FORCEPROP 0 LASTPIN (-2975 2075) $PN BL17
J 2
(-2985 2085);
DISPLAY 0.680851 (-2985 2085);
PAINT MONO (-2985 2085);
FORCEPROP 0 LASTPIN (-2975 1925) $PN BL5
J 2
(-2985 1935);
DISPLAY 0.680851 (-2985 1935);
PAINT MONO (-2985 1935);
FORCEPROP 0 LASTPIN (-2975 2125) $PN BL68
J 2
(-2985 2135);
DISPLAY 0.680851 (-2985 2135);
PAINT MONO (-2985 2135);
FORCEPROP 0 LASTPIN (-2975 2175) $PN BL70
J 2
(-2985 2185);
DISPLAY 0.680851 (-2985 2185);
PAINT MONO (-2985 2185);
FORCEPROP 0 LASTPIN (-2975 2225) $PN BL72
J 2
(-2985 2235);
DISPLAY 0.680851 (-2985 2235);
PAINT MONO (-2985 2235);
FORCEPROP 0 LASTPIN (-2975 2275) $PN BL78
J 2
(-2985 2285);
DISPLAY 0.680851 (-2985 2285);
PAINT MONO (-2985 2285);
FORCEPROP 0 LASTPIN (-2975 1975) $PN BL9
J 2
(-2985 1985);
DISPLAY 0.680851 (-2985 1985);
PAINT MONO (-2985 1985);
FORCEPROP 0 LASTPIN (-2975 2425) $PN BM12
J 2
(-2985 2435);
DISPLAY 0.680851 (-2985 2435);
PAINT MONO (-2985 2435);
FORCEPROP 0 LASTPIN (-2975 2475) $PN BM16
J 2
(-2985 2485);
DISPLAY 0.680851 (-2985 2485);
PAINT MONO (-2985 2485);
FORCEPROP 0 LASTPIN (-2975 2525) $PN BM20
J 2
(-2985 2535);
DISPLAY 0.680851 (-2985 2535);
PAINT MONO (-2985 2535);
FORCEPROP 0 LASTPIN (-2975 2575) $PN BM22
J 2
(-2985 2585);
DISPLAY 0.680851 (-2985 2585);
PAINT MONO (-2985 2585);
FORCEPROP 0 LASTPIN (-2975 2625) $PN BM24
J 2
(-2985 2635);
DISPLAY 0.680851 (-2985 2635);
PAINT MONO (-2985 2635);
FORCEPROP 0 LASTPIN (-2975 2675) $PN BM26
J 2
(-2985 2685);
DISPLAY 0.680851 (-2985 2685);
PAINT MONO (-2985 2685);
FORCEPROP 0 LASTPIN (-2975 2325) $PN BM4
J 2
(-2985 2335);
DISPLAY 0.680851 (-2985 2335);
PAINT MONO (-2985 2335);
FORCEPROP 0 LASTPIN (-2975 2725) $PN BM61
J 2
(-2985 2735);
DISPLAY 0.680851 (-2985 2735);
PAINT MONO (-2985 2735);
FORCEPROP 0 LASTPIN (-2975 2775) $PN BM73
J 2
(-2985 2785);
DISPLAY 0.680851 (-2985 2785);
PAINT MONO (-2985 2785);
FORCEPROP 0 LASTPIN (-2975 2825) $PN BM77
J 2
(-2985 2835);
DISPLAY 0.680851 (-2985 2835);
PAINT MONO (-2985 2835);
FORCEPROP 0 LASTPIN (-2975 2375) $PN BM8
J 2
(-2985 2385);
DISPLAY 0.680851 (-2985 2385);
PAINT MONO (-2985 2385);
FORCEPROP 0 LASTPIN (-2975 2875) $PN BN31
J 2
(-2985 2885);
DISPLAY 0.680851 (-2985 2885);
PAINT MONO (-2985 2885);
FORCEPROP 0 LASTPIN (-2975 2925) $PN BN62
J 2
(-2985 2935);
DISPLAY 0.680851 (-2985 2935);
PAINT MONO (-2985 2935);
FORCEPROP 0 LASTPIN (-2975 2975) $PN BN70
J 2
(-2985 2985);
DISPLAY 0.680851 (-2985 2985);
PAINT MONO (-2985 2985);
FORCEPROP 0 LASTPIN (-2975 3175) $PN BP12
J 2
(-2985 3185);
DISPLAY 0.680851 (-2985 3185);
PAINT MONO (-2985 3185);
FORCEPROP 0 LASTPIN (-2975 3225) $PN BP16
J 2
(-2985 3235);
DISPLAY 0.680851 (-2985 3235);
PAINT MONO (-2985 3235);
FORCEPROP 0 LASTPIN (-2975 3025) $PN BP2
J 2
(-2985 3035);
DISPLAY 0.680851 (-2985 3035);
PAINT MONO (-2985 3035);
FORCEPROP 0 LASTPIN (-2975 3275) $PN BP20
J 2
(-2985 3285);
DISPLAY 0.680851 (-2985 3285);
PAINT MONO (-2985 3285);
FORCEPROP 0 LASTPIN (-2975 3075) $PN BP4
J 2
(-2985 3085);
DISPLAY 0.680851 (-2985 3085);
PAINT MONO (-2985 3085);
FORCEPROP 0 LASTPIN (-2975 3325) $PN BP63
J 2
(-2985 3335);
DISPLAY 0.680851 (-2985 3335);
PAINT MONO (-2985 3335);
FORCEPROP 0 LASTPIN (-2975 3375) $PN BP71
J 2
(-2985 3385);
DISPLAY 0.680851 (-2985 3385);
PAINT MONO (-2985 3385);
FORCEPROP 0 LASTPIN (-2975 3425) $PN BP73
J 2
(-2985 3435);
DISPLAY 0.680851 (-2985 3435);
PAINT MONO (-2985 3435);
FORCEPROP 0 LASTPIN (-2975 3475) $PN BP75
J 2
(-2985 3485);
DISPLAY 0.680851 (-2985 3485);
PAINT MONO (-2985 3485);
FORCEPROP 0 LASTPIN (-2975 3525) $PN BP77
J 2
(-2985 3535);
DISPLAY 0.680851 (-2985 3535);
PAINT MONO (-2985 3535);
FORCEPROP 0 LASTPIN (-2975 3125) $PN BP8
J 2
(-2985 3135);
DISPLAY 0.680851 (-2985 3135);
PAINT MONO (-2985 3135);
FORCEPROP 0 LASTPIN (-2975 3675) $PN BR13
J 2
(-2985 3685);
DISPLAY 0.680851 (-2985 3685);
PAINT MONO (-2985 3685);
FORCEPROP 0 LASTPIN (-2975 3725) $PN BR17
J 2
(-2985 3735);
DISPLAY 0.680851 (-2985 3735);
PAINT MONO (-2985 3735);
FORCEPROP 0 LASTPIN (-2975 3775) $PN BR27
J 2
(-2985 3785);
DISPLAY 0.680851 (-2985 3785);
PAINT MONO (-2985 3785);
FORCEPROP 0 LASTPIN (-2975 3825) $PN BR29
J 2
(-2985 3835);
DISPLAY 0.680851 (-2985 3835);
PAINT MONO (-2985 3835);
FORCEPROP 0 LASTPIN (-2975 3875) $PN BR31
J 2
(-2985 3885);
DISPLAY 0.680851 (-2985 3885);
PAINT MONO (-2985 3885);
FORCEPROP 0 LASTPIN (-2975 3925) $PN BR33
J 2
(-2985 3935);
DISPLAY 0.680851 (-2985 3935);
PAINT MONO (-2985 3935);
FORCEPROP 0 LASTPIN (-2975 3625) $PN BR9
J 2
(-2985 3635);
DISPLAY 0.680851 (-2985 3635);
PAINT MONO (-2985 3635);
FORCEPROP 2 LAST CDS_LIB pure_quanta
J 0
(-1775 1950);
DISPLAY INVISIBLE (-1775 1950);
FORCEPROP 1 LAST NEEDS_NO_SIZE TRUE
J 0
(-1775 1950);
DISPLAY 0.723404 (-1775 1950);
PAINT GREEN (-1775 1950);
DISPLAY INVISIBLE (-1775 1950);
FORCEPROP 1 LAST CDS_LMAN_SYM_OUTLINE -1050,2150,1050,-2100
J 0
(-1775 1950);
DISPLAY 0.468085 (-1775 1950);
PAINT GREEN (-1775 1950);
DISPLAY INVISIBLE (-1775 1950);
FORCEPROP 2 LAST CDS_LOCATION U2
J 0
(-2825 4425);
DISPLAY 1.021277 (-2825 4425);
DISPLAY INVISIBLE (-2825 4425);
FORCEPROP 0 LAST $SEC 37
J 0
(-2825 4425);
DISPLAY 0.680851 (-2825 4425);
PAINT MONO (-2825 4425);
DISPLAY INVISIBLE (-2825 4425);
FORCEPROP 2 LAST CDS_SEC 37
J 0
(-2825 4425);
DISPLAY 1.021277 (-2825 4425);
DISPLAY INVISIBLE (-2825 4425);
FORCEPROP 1 LAST PATH I9
J 0
(-1775 1950);
DISPLAY 0.723404 (-1775 1950);
PAINT GREEN (-1775 1950);
DISPLAY INVISIBLE (-1775 1950);
FORCEADD QUANTA_TITLE_BLOCK_C..1
(5950 -1425);
FORCEPROP 0 LAST CDS_CON_LAST_MODIFIED Fri Aug 25 14:00:24 2023
J 0
(4065 -1410);
PAINT MONO (4065 -1410);
DISPLAY INVISIBLE (4065 -1410);
FORCEPROP 1 LAST CUSTOM_TXT_CDS <CON_LAST_MODIFIED>
J 0
(4065 -1410);
DISPLAY 0.978723 (4065 -1410);
FORCEPROP 2 LAST CUSTOM_TXT_CDS <XR_PAGE_TITLE>
J 0
(-1940 3825);
DISPLAY 0.638298 (-1940 3825);
PAINT PINK (-1940 3825);
DISPLAY INVISIBLE (-1940 3825);
FORCEPROP 2 LAST CUSTOM_TXT_CDS <Q_NUMBER>
J 0
(4547 -1322);
DISPLAY 1.212766 (4547 -1322);
FORCEPROP 1 LAST CUSTOM_TXT_CDS <NAME_2>
J 0
(2775 -1375);
FORCEPROP 1 LAST CUSTOM_TXT_CDS <NAME_1>
J 0
(2775 -1250);
FORCEPROP 1 LAST CUSTOM_TXT_CDS <Q_PROJ>
J 0
(3568 -1323);
DISPLAY 1.212766 (3568 -1323);
FORCEPROP 1 LAST CUSTOM_TXT_CDS <Q_REV>
J 0
(5766 -1322);
DISPLAY 1.212766 (5766 -1322);
FORCEPROP 1 LAST CUSTOM_TXT_CDS <CON_PAGE_NUM> OF <CON_TOTAL_PAGES>
J 0
(5504 -1407);
DISPLAY 0.978723 (5504 -1407);
FORCEPROP 1 LAST Q_TITLE SPR CPU0 POWER - GND (29 OF 30)
J 0
(-3416 -1399);
DISPLAY 1.957447 (-3416 -1399);
PAINT GREEN (-3416 -1399);
FORCEPROP 1 LAST Q_DEPT 
J 1
(2187 -1376);
DISPLAY 1.957447 (2187 -1376);
PAINT GREEN (2187 -1376);
FORCEPROP 2 LAST CDS_LIB pure_quanta
J 0
(5950 -1425);
PAINT MONO (5950 -1425);
DISPLAY INVISIBLE (5950 -1425);
FORCEPROP 1 LAST CDS_LMAN_SYM_OUTLINE -9475,6775,100,-125
J 0
(5950 -1425);
DISPLAY 0.468085 (5950 -1425);
PAINT GREEN (5950 -1425);
DISPLAY INVISIBLE (5950 -1425);
FORCEPROP 2 LAST PAGE_BORDER TRUE
J 0
(-1940 3825);
DISPLAY 0.638298 (-1940 3825);
PAINT PINK (-1940 3825);
DISPLAY INVISIBLE (-1940 3825);
FORCEPROP 2 LAST CDS_XR_PAGE_TITLE CR-41 : @S9S_MB_2U_LIB.S9S_MB_2U(SCH_1):PAGE41
J 0
(-1940 3825);
DISPLAY 0.638298 (-1940 3825);
PAINT PINK (-1940 3825);
DISPLAY INVISIBLE (-1940 3825);
FORCEPROP 1 LAST COMMENT_BODY TRUE
J 0
(5962 -1438);
DISPLAY 0.978723 (5962 -1438);
PAINT GREEN (5962 -1438);
DISPLAY INVISIBLE (5962 -1438);
WIRE 16 -1 (5750 -25)(5750 -525);
WIRE 16 -1 (5750 25)(5750 -25);
WIRE 16 -1 (5500 -25)(5750 -25);
WIRE 16 -1 (2850 -25)(2850 -525);
WIRE 16 -1 (2850 25)(2850 -25);
WIRE 16 -1 (2850 -25)(3100 -25);
WIRE 16 -1 (2725 -25)(2725 -525);
WIRE 16 -1 (2725 25)(2725 -25);
WIRE 16 -1 (2475 -25)(2725 -25);
WIRE 16 -1 (-175 -25)(-175 -525);
WIRE 16 -1 (-175 25)(-175 -25);
WIRE 16 -1 (-175 -25)(75 -25);
WIRE 16 -1 (-325 -25)(-325 -525);
WIRE 16 -1 (-325 25)(-325 -25);
WIRE 16 -1 (-575 -25)(-325 -25);
WIRE 16 -1 (-3225 -25)(-3225 -525);
WIRE 16 -1 (-3225 25)(-3225 -25);
WIRE 16 -1 (-3225 -25)(-2975 -25);
WIRE 16 -1 (3100 3925)(2850 3925);
WIRE 16 -1 (2850 3925)(2850 3875);
WIRE 16 -1 (3100 3875)(2850 3875);
WIRE 16 -1 (2850 3875)(2850 3825);
WIRE 16 -1 (3100 3825)(2850 3825);
WIRE 16 -1 (2850 3825)(2850 3775);
WIRE 16 -1 (3100 3775)(2850 3775);
WIRE 16 -1 (2850 3775)(2850 3725);
WIRE 16 -1 (3100 3725)(2850 3725);
WIRE 16 -1 (2850 3725)(2850 3675);
WIRE 16 -1 (3100 3675)(2850 3675);
WIRE 16 -1 (2850 3675)(2850 3625);
WIRE 16 -1 (3100 3625)(2850 3625);
WIRE 16 -1 (2850 3625)(2850 3575);
WIRE 16 -1 (3100 3575)(2850 3575);
WIRE 16 -1 (2850 3575)(2850 3525);
WIRE 16 -1 (3100 3525)(2850 3525);
WIRE 16 -1 (2850 3525)(2850 3475);
WIRE 16 -1 (3100 3475)(2850 3475);
WIRE 16 -1 (2850 3475)(2850 3425);
WIRE 16 -1 (3100 3425)(2850 3425);
WIRE 16 -1 (2850 3425)(2850 3375);
WIRE 16 -1 (3100 3375)(2850 3375);
WIRE 16 -1 (2850 3375)(2850 3325);
WIRE 16 -1 (3100 3325)(2850 3325);
WIRE 16 -1 (2850 3325)(2850 3275);
WIRE 16 -1 (3100 3275)(2850 3275);
WIRE 16 -1 (2850 3275)(2850 3225);
WIRE 16 -1 (2850 3225)(3100 3225);
WIRE 16 -1 (2850 3225)(2850 3175);
WIRE 16 -1 (2850 3175)(3100 3175);
WIRE 16 -1 (2850 3175)(2850 3125);
WIRE 16 -1 (2850 3125)(3100 3125);
WIRE 16 -1 (2850 3125)(2850 3075);
WIRE 16 -1 (2850 3075)(3100 3075);
WIRE 16 -1 (2850 3075)(2850 3025);
WIRE 16 -1 (2850 3025)(3100 3025);
WIRE 16 -1 (2850 3025)(2850 2975);
WIRE 16 -1 (2850 2975)(3100 2975);
WIRE 16 -1 (2850 2975)(2850 2925);
WIRE 16 -1 (2850 2925)(3100 2925);
WIRE 16 -1 (2850 2925)(2850 2875);
WIRE 16 -1 (2850 2875)(3100 2875);
WIRE 16 -1 (2850 2875)(2850 2825);
WIRE 16 -1 (2850 2825)(3100 2825);
WIRE 16 -1 (2850 2825)(2850 2775);
WIRE 16 -1 (2850 2775)(3100 2775);
WIRE 16 -1 (2850 2775)(2850 2725);
WIRE 16 -1 (2850 2725)(3100 2725);
WIRE 16 -1 (2850 2725)(2850 2675);
WIRE 16 -1 (2850 2675)(3100 2675);
WIRE 16 -1 (2850 2675)(2850 2625);
WIRE 16 -1 (2850 2625)(3100 2625);
WIRE 16 -1 (2850 2625)(2850 2575);
WIRE 16 -1 (2850 2575)(3100 2575);
WIRE 16 -1 (2850 2575)(2850 2525);
WIRE 16 -1 (2850 2525)(3100 2525);
WIRE 16 -1 (2850 2525)(2850 2475);
WIRE 16 -1 (2850 2475)(3100 2475);
WIRE 16 -1 (2850 2475)(2850 2425);
WIRE 16 -1 (2850 2425)(3100 2425);
WIRE 16 -1 (2850 2425)(2850 2375);
WIRE 16 -1 (2850 2375)(3100 2375);
WIRE 16 -1 (2850 2375)(2850 2325);
WIRE 16 -1 (2850 2325)(3100 2325);
WIRE 16 -1 (2850 2325)(2850 2275);
WIRE 16 -1 (2850 2275)(3100 2275);
WIRE 16 -1 (2850 2275)(2850 2225);
WIRE 16 -1 (2850 2225)(3100 2225);
WIRE 16 -1 (2850 2225)(2850 2175);
WIRE 16 -1 (2850 2175)(3100 2175);
WIRE 16 -1 (2850 2175)(2850 2125);
WIRE 16 -1 (2850 2125)(3100 2125);
WIRE 16 -1 (2850 2125)(2850 2075);
WIRE 16 -1 (2850 2075)(3100 2075);
WIRE 16 -1 (2850 2025)(3100 2025);
WIRE 16 -1 (2850 2075)(2850 2025);
WIRE 16 -1 (2850 2025)(2850 1975);
WIRE 16 -1 (2850 1975)(3100 1975);
WIRE 16 -1 (2850 1975)(2850 1925);
WIRE 16 -1 (2850 1925)(3100 1925);
WIRE 16 -1 (2850 1925)(2850 1875);
WIRE 16 -1 (3100 1875)(2850 1875);
WIRE 16 -1 (2850 1875)(2850 1825);
WIRE 16 -1 (2850 1825)(3100 1825);
WIRE 16 -1 (2850 1825)(2850 1775);
WIRE 16 -1 (2850 1775)(3100 1775);
WIRE 16 -1 (2850 1775)(2850 1725);
WIRE 16 -1 (2850 1725)(3100 1725);
WIRE 16 -1 (2850 1725)(2850 1675);
WIRE 16 -1 (2850 1675)(3100 1675);
WIRE 16 -1 (2850 1675)(2850 1625);
WIRE 16 -1 (2850 1625)(3100 1625);
WIRE 16 -1 (2850 1625)(2850 1575);
WIRE 16 -1 (2850 1575)(3100 1575);
WIRE 16 -1 (2850 1575)(2850 1525);
WIRE 16 -1 (2850 1525)(3100 1525);
WIRE 16 -1 (2850 1525)(2850 1475);
WIRE 16 -1 (2850 1475)(3100 1475);
WIRE 16 -1 (2850 1475)(2850 1425);
WIRE 16 -1 (2850 1425)(3100 1425);
WIRE 16 -1 (2850 1425)(2850 1375);
WIRE 16 -1 (2850 1375)(3100 1375);
WIRE 16 -1 (2850 1375)(2850 1325);
WIRE 16 -1 (2850 1325)(3100 1325);
WIRE 16 -1 (2850 1325)(2850 1275);
WIRE 16 -1 (2850 1275)(3100 1275);
WIRE 16 -1 (2850 1275)(2850 1225);
WIRE 16 -1 (2850 1225)(3100 1225);
WIRE 16 -1 (2850 1225)(2850 1175);
WIRE 16 -1 (2850 1175)(3100 1175);
WIRE 16 -1 (2850 1175)(2850 1125);
WIRE 16 -1 (2850 1125)(3100 1125);
WIRE 16 -1 (2850 1125)(2850 1075);
WIRE 16 -1 (2850 1075)(3100 1075);
WIRE 16 -1 (2850 1075)(2850 1025);
WIRE 16 -1 (2850 1025)(3100 1025);
WIRE 16 -1 (2850 1025)(2850 975);
WIRE 16 -1 (2850 975)(3100 975);
WIRE 16 -1 (2850 975)(2850 925);
WIRE 16 -1 (2850 925)(3100 925);
WIRE 16 -1 (2850 925)(2850 875);
WIRE 16 -1 (3100 875)(2850 875);
WIRE 16 -1 (2850 875)(2850 825);
WIRE 16 -1 (2850 825)(3100 825);
WIRE 16 -1 (2850 825)(2850 775);
WIRE 16 -1 (2850 775)(3100 775);
WIRE 16 -1 (2850 775)(2850 725);
WIRE 16 -1 (2850 725)(3100 725);
WIRE 16 -1 (2850 725)(2850 675);
WIRE 16 -1 (2850 675)(3100 675);
WIRE 16 -1 (2850 675)(2850 625);
WIRE 16 -1 (2850 625)(3100 625);
WIRE 16 -1 (2850 625)(2850 575);
WIRE 16 -1 (3100 575)(2850 575);
WIRE 16 -1 (2850 575)(2850 525);
WIRE 16 -1 (2850 525)(3100 525);
WIRE 16 -1 (2850 525)(2850 475);
WIRE 16 -1 (2850 475)(3100 475);
WIRE 16 -1 (2850 475)(2850 425);
WIRE 16 -1 (2850 425)(3100 425);
WIRE 16 -1 (2850 425)(2850 375);
WIRE 16 -1 (2850 375)(3100 375);
WIRE 16 -1 (2850 375)(2850 325);
WIRE 16 -1 (2850 325)(3100 325);
WIRE 16 -1 (2850 325)(2850 275);
WIRE 16 -1 (2850 275)(3100 275);
WIRE 16 -1 (2850 275)(2850 225);
WIRE 16 -1 (3100 225)(2850 225);
WIRE 16 -1 (2850 225)(2850 175);
WIRE 16 -1 (2850 175)(3100 175);
WIRE 16 -1 (2850 175)(2850 125);
WIRE 16 -1 (2850 125)(3100 125);
WIRE 16 -1 (2850 125)(2850 75);
WIRE 16 -1 (2850 75)(3100 75);
WIRE 16 -1 (2850 75)(2850 25);
WIRE 16 -1 (2850 25)(3100 25);
WIRE 16 -1 (5750 3925)(5500 3925);
WIRE 16 -1 (5750 3875)(5500 3875);
WIRE 16 -1 (5750 3925)(5750 3875);
WIRE 16 -1 (5750 3825)(5500 3825);
WIRE 16 -1 (5750 3875)(5750 3825);
WIRE 16 -1 (5750 3775)(5500 3775);
WIRE 16 -1 (5750 3825)(5750 3775);
WIRE 16 -1 (5500 3725)(5750 3725);
WIRE 16 -1 (5750 3725)(5750 3775);
WIRE 16 -1 (5750 3675)(5500 3675);
WIRE 16 -1 (5750 3675)(5750 3725);
WIRE 16 -1 (5750 3625)(5500 3625);
WIRE 16 -1 (5750 3675)(5750 3625);
WIRE 16 -1 (5750 3575)(5500 3575);
WIRE 16 -1 (5750 3625)(5750 3575);
WIRE 16 -1 (5750 3525)(5500 3525);
WIRE 16 -1 (5750 3575)(5750 3525);
WIRE 16 -1 (5750 3475)(5500 3475);
WIRE 16 -1 (5750 3525)(5750 3475);
WIRE 16 -1 (5750 3425)(5500 3425);
WIRE 16 -1 (5750 3475)(5750 3425);
WIRE 16 -1 (5750 3375)(5500 3375);
WIRE 16 -1 (5750 3425)(5750 3375);
WIRE 16 -1 (5750 3325)(5500 3325);
WIRE 16 -1 (5750 3375)(5750 3325);
WIRE 16 -1 (5750 3275)(5500 3275);
WIRE 16 -1 (5750 3325)(5750 3275);
WIRE 16 -1 (5500 3225)(5750 3225);
WIRE 16 -1 (5750 3275)(5750 3225);
WIRE 16 -1 (5500 3175)(5750 3175);
WIRE 16 -1 (5750 3225)(5750 3175);
WIRE 16 -1 (5500 3125)(5750 3125);
WIRE 16 -1 (5750 3175)(5750 3125);
WIRE 16 -1 (5500 3075)(5750 3075);
WIRE 16 -1 (5750 3125)(5750 3075);
WIRE 16 -1 (5500 3025)(5750 3025);
WIRE 16 -1 (5750 3075)(5750 3025);
WIRE 16 -1 (5500 2975)(5750 2975);
WIRE 16 -1 (5750 3025)(5750 2975);
WIRE 16 -1 (5500 2925)(5750 2925);
WIRE 16 -1 (5750 2975)(5750 2925);
WIRE 16 -1 (5500 2875)(5750 2875);
WIRE 16 -1 (5750 2875)(5750 2925);
WIRE 16 -1 (5500 2825)(5750 2825);
WIRE 16 -1 (5750 2875)(5750 2825);
WIRE 16 -1 (5750 2775)(5500 2775);
WIRE 16 -1 (5750 2825)(5750 2775);
WIRE 16 -1 (5750 2725)(5500 2725);
WIRE 16 -1 (5750 2775)(5750 2725);
WIRE 16 -1 (5750 2675)(5500 2675);
WIRE 16 -1 (5750 2725)(5750 2675);
WIRE 16 -1 (5750 2625)(5500 2625);
WIRE 16 -1 (5750 2675)(5750 2625);
WIRE 16 -1 (5500 2575)(5750 2575);
WIRE 16 -1 (5750 2575)(5750 2625);
WIRE 16 -1 (5750 2525)(5500 2525);
WIRE 16 -1 (5750 2525)(5750 2575);
WIRE 16 -1 (5750 2475)(5500 2475);
WIRE 16 -1 (5750 2525)(5750 2475);
WIRE 16 -1 (5750 2425)(5500 2425);
WIRE 16 -1 (5750 2475)(5750 2425);
WIRE 16 -1 (5750 2375)(5500 2375);
WIRE 16 -1 (5750 2425)(5750 2375);
WIRE 16 -1 (5750 2325)(5500 2325);
WIRE 16 -1 (5750 2375)(5750 2325);
WIRE 16 -1 (5750 2275)(5500 2275);
WIRE 16 -1 (5750 2325)(5750 2275);
WIRE 16 -1 (5750 2225)(5500 2225);
WIRE 16 -1 (5750 2275)(5750 2225);
WIRE 16 -1 (5750 2175)(5500 2175);
WIRE 16 -1 (5750 2225)(5750 2175);
WIRE 16 -1 (5750 2125)(5500 2125);
WIRE 16 -1 (5750 2175)(5750 2125);
WIRE 16 -1 (5500 2075)(5750 2075);
WIRE 16 -1 (5750 2125)(5750 2075);
WIRE 16 -1 (5500 2025)(5750 2025);
WIRE 16 -1 (5750 2075)(5750 2025);
WIRE 16 -1 (5500 1975)(5750 1975);
WIRE 16 -1 (5750 2025)(5750 1975);
WIRE 16 -1 (5500 1925)(5750 1925);
WIRE 16 -1 (5750 1975)(5750 1925);
WIRE 16 -1 (5500 1875)(5750 1875);
WIRE 16 -1 (5750 1925)(5750 1875);
WIRE 16 -1 (5500 1825)(5750 1825);
WIRE 16 -1 (5750 1875)(5750 1825);
WIRE 16 -1 (5500 1775)(5750 1775);
WIRE 16 -1 (5750 1825)(5750 1775);
WIRE 16 -1 (5500 1725)(5750 1725);
WIRE 16 -1 (5750 1725)(5750 1775);
WIRE 16 -1 (5500 1675)(5750 1675);
WIRE 16 -1 (5750 1725)(5750 1675);
WIRE 16 -1 (5750 1625)(5500 1625);
WIRE 16 -1 (5750 1675)(5750 1625);
WIRE 16 -1 (5750 1575)(5500 1575);
WIRE 16 -1 (5750 1625)(5750 1575);
WIRE 16 -1 (5750 1525)(5500 1525);
WIRE 16 -1 (5750 1575)(5750 1525);
WIRE 16 -1 (5750 1475)(5500 1475);
WIRE 16 -1 (5750 1525)(5750 1475);
WIRE 16 -1 (5500 1425)(5750 1425);
WIRE 16 -1 (5750 1425)(5750 1475);
WIRE 16 -1 (5750 1375)(5500 1375);
WIRE 16 -1 (5750 1375)(5750 1425);
WIRE 16 -1 (5750 1325)(5500 1325);
WIRE 16 -1 (5750 1375)(5750 1325);
WIRE 16 -1 (5750 1275)(5500 1275);
WIRE 16 -1 (5750 1325)(5750 1275);
WIRE 16 -1 (5500 1225)(5750 1225);
WIRE 16 -1 (5750 1275)(5750 1225);
WIRE 16 -1 (5500 1175)(5750 1175);
WIRE 16 -1 (5750 1225)(5750 1175);
WIRE 16 -1 (5500 1125)(5750 1125);
WIRE 16 -1 (5750 1175)(5750 1125);
WIRE 16 -1 (5500 1075)(5750 1075);
WIRE 16 -1 (5750 1125)(5750 1075);
WIRE 16 -1 (5500 1025)(5750 1025);
WIRE 16 -1 (5750 1075)(5750 1025);
WIRE 16 -1 (5500 975)(5750 975);
WIRE 16 -1 (5750 1025)(5750 975);
WIRE 16 -1 (5500 925)(5750 925);
WIRE 16 -1 (5750 975)(5750 925);
WIRE 16 -1 (5500 875)(5750 875);
WIRE 16 -1 (5750 875)(5750 925);
WIRE 16 -1 (5500 825)(5750 825);
WIRE 16 -1 (5750 875)(5750 825);
WIRE 16 -1 (5750 775)(5500 775);
WIRE 16 -1 (5750 825)(5750 775);
WIRE 16 -1 (5750 725)(5500 725);
WIRE 16 -1 (5750 775)(5750 725);
WIRE 16 -1 (5750 675)(5500 675);
WIRE 16 -1 (5750 725)(5750 675);
WIRE 16 -1 (5750 625)(5500 625);
WIRE 16 -1 (5750 675)(5750 625);
WIRE 16 -1 (5500 575)(5750 575);
WIRE 16 -1 (5750 575)(5750 625);
WIRE 16 -1 (5750 525)(5500 525);
WIRE 16 -1 (5750 525)(5750 575);
WIRE 16 -1 (5750 475)(5500 475);
WIRE 16 -1 (5750 525)(5750 475);
WIRE 16 -1 (5750 425)(5500 425);
WIRE 16 -1 (5750 475)(5750 425);
WIRE 16 -1 (5500 375)(5750 375);
WIRE 16 -1 (5750 425)(5750 375);
WIRE 16 -1 (5500 325)(5750 325);
WIRE 16 -1 (5750 375)(5750 325);
WIRE 16 -1 (5500 275)(5750 275);
WIRE 16 -1 (5750 325)(5750 275);
WIRE 16 -1 (5500 225)(5750 225);
WIRE 16 -1 (5750 275)(5750 225);
WIRE 16 -1 (5500 175)(5750 175);
WIRE 16 -1 (5750 225)(5750 175);
WIRE 16 -1 (5500 125)(5750 125);
WIRE 16 -1 (5750 175)(5750 125);
WIRE 16 -1 (5500 75)(5750 75);
WIRE 16 -1 (5750 125)(5750 75);
WIRE 16 -1 (5750 25)(5750 75);
WIRE 16 -1 (5500 25)(5750 25);
WIRE 16 -1 (75 3925)(-175 3925);
WIRE 16 -1 (-175 3925)(-175 3875);
WIRE 16 -1 (75 3875)(-175 3875);
WIRE 16 -1 (-175 3875)(-175 3825);
WIRE 16 -1 (75 3825)(-175 3825);
WIRE 16 -1 (-175 3825)(-175 3775);
WIRE 16 -1 (75 3775)(-175 3775);
WIRE 16 -1 (-175 3775)(-175 3725);
WIRE 16 -1 (75 3725)(-175 3725);
WIRE 16 -1 (-175 3725)(-175 3675);
WIRE 16 -1 (75 3675)(-175 3675);
WIRE 16 -1 (-175 3675)(-175 3625);
WIRE 16 -1 (75 3625)(-175 3625);
WIRE 16 -1 (-175 3625)(-175 3575);
WIRE 16 -1 (75 3575)(-175 3575);
WIRE 16 -1 (-175 3575)(-175 3525);
WIRE 16 -1 (75 3525)(-175 3525);
WIRE 16 -1 (-175 3525)(-175 3475);
WIRE 16 -1 (75 3475)(-175 3475);
WIRE 16 -1 (-175 3475)(-175 3425);
WIRE 16 -1 (75 3425)(-175 3425);
WIRE 16 -1 (-175 3425)(-175 3375);
WIRE 16 -1 (75 3375)(-175 3375);
WIRE 16 -1 (-175 3375)(-175 3325);
WIRE 16 -1 (75 3325)(-175 3325);
WIRE 16 -1 (-175 3325)(-175 3275);
WIRE 16 -1 (75 3275)(-175 3275);
WIRE 16 -1 (-175 3275)(-175 3225);
WIRE 16 -1 (-175 3225)(75 3225);
WIRE 16 -1 (-175 3225)(-175 3175);
WIRE 16 -1 (-175 3175)(75 3175);
WIRE 16 -1 (-175 3175)(-175 3125);
WIRE 16 -1 (-175 3125)(75 3125);
WIRE 16 -1 (-175 3125)(-175 3075);
WIRE 16 -1 (-175 3075)(75 3075);
WIRE 16 -1 (-175 3075)(-175 3025);
WIRE 16 -1 (-175 3025)(75 3025);
WIRE 16 -1 (-175 3025)(-175 2975);
WIRE 16 -1 (-175 2975)(75 2975);
WIRE 16 -1 (-175 2975)(-175 2925);
WIRE 16 -1 (-175 2925)(75 2925);
WIRE 16 -1 (-175 2925)(-175 2875);
WIRE 16 -1 (-175 2875)(75 2875);
WIRE 16 -1 (-175 2875)(-175 2825);
WIRE 16 -1 (-175 2825)(75 2825);
WIRE 16 -1 (-175 2825)(-175 2775);
WIRE 16 -1 (-175 2775)(75 2775);
WIRE 16 -1 (-175 2775)(-175 2725);
WIRE 16 -1 (-175 2725)(75 2725);
WIRE 16 -1 (-175 2725)(-175 2675);
WIRE 16 -1 (-175 2675)(75 2675);
WIRE 16 -1 (-175 2675)(-175 2625);
WIRE 16 -1 (-175 2625)(75 2625);
WIRE 16 -1 (-175 2625)(-175 2575);
WIRE 16 -1 (-175 2575)(75 2575);
WIRE 16 -1 (-175 2575)(-175 2525);
WIRE 16 -1 (-175 2525)(75 2525);
WIRE 16 -1 (-175 2525)(-175 2475);
WIRE 16 -1 (-175 2475)(75 2475);
WIRE 16 -1 (-175 2475)(-175 2425);
WIRE 16 -1 (-175 2425)(75 2425);
WIRE 16 -1 (-175 2425)(-175 2375);
WIRE 16 -1 (-175 2375)(75 2375);
WIRE 16 -1 (-175 2375)(-175 2325);
WIRE 16 -1 (-175 2325)(75 2325);
WIRE 16 -1 (-175 2325)(-175 2275);
WIRE 16 -1 (-175 2275)(75 2275);
WIRE 16 -1 (-175 2275)(-175 2225);
WIRE 16 -1 (-175 2225)(75 2225);
WIRE 16 -1 (-175 2225)(-175 2175);
WIRE 16 -1 (-175 2175)(75 2175);
WIRE 16 -1 (-175 2175)(-175 2125);
WIRE 16 -1 (-175 2125)(75 2125);
WIRE 16 -1 (-175 2125)(-175 2075);
WIRE 16 -1 (-175 2075)(75 2075);
WIRE 16 -1 (-175 2075)(-175 2025);
WIRE 16 -1 (-175 2025)(75 2025);
WIRE 16 -1 (-175 2025)(-175 1975);
WIRE 16 -1 (-175 1975)(75 1975);
WIRE 16 -1 (-175 1975)(-175 1925);
WIRE 16 -1 (-175 1925)(75 1925);
WIRE 16 -1 (-175 1925)(-175 1875);
WIRE 16 -1 (75 1875)(-175 1875);
WIRE 16 -1 (-175 1875)(-175 1825);
WIRE 16 -1 (-175 1825)(75 1825);
WIRE 16 -1 (-175 1825)(-175 1775);
WIRE 16 -1 (-175 1775)(75 1775);
WIRE 16 -1 (-175 1775)(-175 1725);
WIRE 16 -1 (-175 1725)(75 1725);
WIRE 16 -1 (-175 1725)(-175 1675);
WIRE 16 -1 (-175 1675)(75 1675);
WIRE 16 -1 (-175 1675)(-175 1625);
WIRE 16 -1 (-175 1625)(75 1625);
WIRE 16 -1 (-175 1625)(-175 1575);
WIRE 16 -1 (-175 1575)(75 1575);
WIRE 16 -1 (-175 1575)(-175 1525);
WIRE 16 -1 (-175 1525)(75 1525);
WIRE 16 -1 (-175 1525)(-175 1475);
WIRE 16 -1 (-175 1475)(75 1475);
WIRE 16 -1 (-175 1475)(-175 1425);
WIRE 16 -1 (-175 1425)(75 1425);
WIRE 16 -1 (-175 1425)(-175 1375);
WIRE 16 -1 (-175 1375)(75 1375);
WIRE 16 -1 (-175 1375)(-175 1325);
WIRE 16 -1 (-175 1325)(75 1325);
WIRE 16 -1 (-175 1325)(-175 1275);
WIRE 16 -1 (-175 1275)(75 1275);
WIRE 16 -1 (-175 1275)(-175 1225);
WIRE 16 -1 (-175 1225)(75 1225);
WIRE 16 -1 (-175 1225)(-175 1175);
WIRE 16 -1 (-175 1175)(75 1175);
WIRE 16 -1 (-175 1175)(-175 1125);
WIRE 16 -1 (-175 1125)(75 1125);
WIRE 16 -1 (-175 1125)(-175 1075);
WIRE 16 -1 (-175 1075)(75 1075);
WIRE 16 -1 (-175 1075)(-175 1025);
WIRE 16 -1 (-175 1025)(75 1025);
WIRE 16 -1 (-175 1025)(-175 975);
WIRE 16 -1 (-175 975)(75 975);
WIRE 16 -1 (-175 975)(-175 925);
WIRE 16 -1 (-175 925)(75 925);
WIRE 16 -1 (-175 925)(-175 875);
WIRE 16 -1 (75 875)(-175 875);
WIRE 16 -1 (-175 875)(-175 825);
WIRE 16 -1 (-175 825)(75 825);
WIRE 16 -1 (-175 825)(-175 775);
WIRE 16 -1 (-175 775)(75 775);
WIRE 16 -1 (-175 775)(-175 725);
WIRE 16 -1 (-175 725)(75 725);
WIRE 16 -1 (-175 725)(-175 675);
WIRE 16 -1 (-175 675)(75 675);
WIRE 16 -1 (-175 675)(-175 625);
WIRE 16 -1 (-175 625)(75 625);
WIRE 16 -1 (-175 625)(-175 575);
WIRE 16 -1 (75 575)(-175 575);
WIRE 16 -1 (-175 575)(-175 525);
WIRE 16 -1 (-175 525)(75 525);
WIRE 16 -1 (-175 525)(-175 475);
WIRE 16 -1 (-175 475)(75 475);
WIRE 16 -1 (-175 475)(-175 425);
WIRE 16 -1 (-175 425)(75 425);
WIRE 16 -1 (-175 425)(-175 375);
WIRE 16 -1 (-175 375)(75 375);
WIRE 16 -1 (-175 375)(-175 325);
WIRE 16 -1 (-175 325)(75 325);
WIRE 16 -1 (-175 325)(-175 275);
WIRE 16 -1 (-175 275)(75 275);
WIRE 16 -1 (-175 275)(-175 225);
WIRE 16 -1 (75 225)(-175 225);
WIRE 16 -1 (-175 225)(-175 175);
WIRE 16 -1 (-175 175)(75 175);
WIRE 16 -1 (-175 175)(-175 125);
WIRE 16 -1 (-175 125)(75 125);
WIRE 16 -1 (-175 125)(-175 75);
WIRE 16 -1 (-175 75)(75 75);
WIRE 16 -1 (-175 75)(-175 25);
WIRE 16 -1 (-175 25)(75 25);
WIRE 16 -1 (2725 3925)(2475 3925);
WIRE 16 -1 (2725 3875)(2475 3875);
WIRE 16 -1 (2725 3925)(2725 3875);
WIRE 16 -1 (2725 3825)(2475 3825);
WIRE 16 -1 (2725 3875)(2725 3825);
WIRE 16 -1 (2725 3775)(2475 3775);
WIRE 16 -1 (2725 3825)(2725 3775);
WIRE 16 -1 (2475 3725)(2725 3725);
WIRE 16 -1 (2725 3725)(2725 3775);
WIRE 16 -1 (2725 3675)(2475 3675);
WIRE 16 -1 (2725 3675)(2725 3725);
WIRE 16 -1 (2725 3625)(2475 3625);
WIRE 16 -1 (2725 3675)(2725 3625);
WIRE 16 -1 (2725 3575)(2475 3575);
WIRE 16 -1 (2725 3625)(2725 3575);
WIRE 16 -1 (2725 3525)(2475 3525);
WIRE 16 -1 (2725 3575)(2725 3525);
WIRE 16 -1 (2725 3475)(2475 3475);
WIRE 16 -1 (2725 3525)(2725 3475);
WIRE 16 -1 (2725 3425)(2475 3425);
WIRE 16 -1 (2725 3475)(2725 3425);
WIRE 16 -1 (2725 3375)(2475 3375);
WIRE 16 -1 (2725 3425)(2725 3375);
WIRE 16 -1 (2725 3325)(2475 3325);
WIRE 16 -1 (2725 3375)(2725 3325);
WIRE 16 -1 (2725 3275)(2475 3275);
WIRE 16 -1 (2725 3325)(2725 3275);
WIRE 16 -1 (2475 3225)(2725 3225);
WIRE 16 -1 (2725 3275)(2725 3225);
WIRE 16 -1 (2475 3175)(2725 3175);
WIRE 16 -1 (2725 3225)(2725 3175);
WIRE 16 -1 (2475 3125)(2725 3125);
WIRE 16 -1 (2725 3175)(2725 3125);
WIRE 16 -1 (2475 3075)(2725 3075);
WIRE 16 -1 (2725 3125)(2725 3075);
WIRE 16 -1 (2475 3025)(2725 3025);
WIRE 16 -1 (2725 3075)(2725 3025);
WIRE 16 -1 (2475 2975)(2725 2975);
WIRE 16 -1 (2725 3025)(2725 2975);
WIRE 16 -1 (2475 2925)(2725 2925);
WIRE 16 -1 (2725 2975)(2725 2925);
WIRE 16 -1 (2475 2875)(2725 2875);
WIRE 16 -1 (2725 2875)(2725 2925);
WIRE 16 -1 (2475 2825)(2725 2825);
WIRE 16 -1 (2725 2875)(2725 2825);
WIRE 16 -1 (2725 2775)(2475 2775);
WIRE 16 -1 (2725 2825)(2725 2775);
WIRE 16 -1 (2725 2725)(2475 2725);
WIRE 16 -1 (2725 2775)(2725 2725);
WIRE 16 -1 (2725 2675)(2475 2675);
WIRE 16 -1 (2725 2725)(2725 2675);
WIRE 16 -1 (2725 2625)(2475 2625);
WIRE 16 -1 (2725 2675)(2725 2625);
WIRE 16 -1 (2475 2575)(2725 2575);
WIRE 16 -1 (2725 2575)(2725 2625);
WIRE 16 -1 (2725 2525)(2475 2525);
WIRE 16 -1 (2725 2525)(2725 2575);
WIRE 16 -1 (2725 2475)(2475 2475);
WIRE 16 -1 (2725 2525)(2725 2475);
WIRE 16 -1 (2725 2425)(2475 2425);
WIRE 16 -1 (2725 2475)(2725 2425);
WIRE 16 -1 (2725 2375)(2475 2375);
WIRE 16 -1 (2725 2425)(2725 2375);
WIRE 16 -1 (2725 2325)(2475 2325);
WIRE 16 -1 (2725 2375)(2725 2325);
WIRE 16 -1 (2725 2275)(2475 2275);
WIRE 16 -1 (2725 2325)(2725 2275);
WIRE 16 -1 (2725 2225)(2475 2225);
WIRE 16 -1 (2725 2275)(2725 2225);
WIRE 16 -1 (2725 2175)(2475 2175);
WIRE 16 -1 (2725 2225)(2725 2175);
WIRE 16 -1 (2725 2125)(2475 2125);
WIRE 16 -1 (2725 2175)(2725 2125);
WIRE 16 -1 (2475 2075)(2725 2075);
WIRE 16 -1 (2725 2125)(2725 2075);
WIRE 16 -1 (2475 2025)(2725 2025);
WIRE 16 -1 (2725 2075)(2725 2025);
WIRE 16 -1 (2475 1975)(2725 1975);
WIRE 16 -1 (2725 2025)(2725 1975);
WIRE 16 -1 (2475 1925)(2725 1925);
WIRE 16 -1 (2725 1975)(2725 1925);
WIRE 16 -1 (2475 1875)(2725 1875);
WIRE 16 -1 (2725 1925)(2725 1875);
WIRE 16 -1 (2475 1825)(2725 1825);
WIRE 16 -1 (2725 1875)(2725 1825);
WIRE 16 -1 (2475 1775)(2725 1775);
WIRE 16 -1 (2725 1825)(2725 1775);
WIRE 16 -1 (2475 1725)(2725 1725);
WIRE 16 -1 (2725 1725)(2725 1775);
WIRE 16 -1 (2475 1675)(2725 1675);
WIRE 16 -1 (2725 1725)(2725 1675);
WIRE 16 -1 (2725 1625)(2475 1625);
WIRE 16 -1 (2725 1675)(2725 1625);
WIRE 16 -1 (2725 1575)(2475 1575);
WIRE 16 -1 (2725 1625)(2725 1575);
WIRE 16 -1 (2725 1525)(2475 1525);
WIRE 16 -1 (2725 1575)(2725 1525);
WIRE 16 -1 (2725 1475)(2475 1475);
WIRE 16 -1 (2725 1525)(2725 1475);
WIRE 16 -1 (2475 1425)(2725 1425);
WIRE 16 -1 (2725 1425)(2725 1475);
WIRE 16 -1 (2725 1375)(2475 1375);
WIRE 16 -1 (2725 1375)(2725 1425);
WIRE 16 -1 (2725 1325)(2475 1325);
WIRE 16 -1 (2725 1375)(2725 1325);
WIRE 16 -1 (2725 1275)(2475 1275);
WIRE 16 -1 (2725 1325)(2725 1275);
WIRE 16 -1 (2475 1225)(2725 1225);
WIRE 16 -1 (2725 1275)(2725 1225);
WIRE 16 -1 (2475 1175)(2725 1175);
WIRE 16 -1 (2725 1225)(2725 1175);
WIRE 16 -1 (2475 1125)(2725 1125);
WIRE 16 -1 (2725 1175)(2725 1125);
WIRE 16 -1 (2475 1075)(2725 1075);
WIRE 16 -1 (2725 1125)(2725 1075);
WIRE 16 -1 (2475 1025)(2725 1025);
WIRE 16 -1 (2725 1075)(2725 1025);
WIRE 16 -1 (2475 975)(2725 975);
WIRE 16 -1 (2725 1025)(2725 975);
WIRE 16 -1 (2475 925)(2725 925);
WIRE 16 -1 (2725 975)(2725 925);
WIRE 16 -1 (2475 875)(2725 875);
WIRE 16 -1 (2725 875)(2725 925);
WIRE 16 -1 (2475 825)(2725 825);
WIRE 16 -1 (2725 875)(2725 825);
WIRE 16 -1 (2725 775)(2475 775);
WIRE 16 -1 (2725 825)(2725 775);
WIRE 16 -1 (2725 725)(2475 725);
WIRE 16 -1 (2725 775)(2725 725);
WIRE 16 -1 (2725 675)(2475 675);
WIRE 16 -1 (2725 725)(2725 675);
WIRE 16 -1 (2725 625)(2475 625);
WIRE 16 -1 (2725 675)(2725 625);
WIRE 16 -1 (2475 575)(2725 575);
WIRE 16 -1 (2725 575)(2725 625);
WIRE 16 -1 (2725 525)(2475 525);
WIRE 16 -1 (2725 525)(2725 575);
WIRE 16 -1 (2725 475)(2475 475);
WIRE 16 -1 (2725 525)(2725 475);
WIRE 16 -1 (2725 425)(2475 425);
WIRE 16 -1 (2725 475)(2725 425);
WIRE 16 -1 (2475 375)(2725 375);
WIRE 16 -1 (2725 425)(2725 375);
WIRE 16 -1 (2475 325)(2725 325);
WIRE 16 -1 (2725 375)(2725 325);
WIRE 16 -1 (2475 275)(2725 275);
WIRE 16 -1 (2725 325)(2725 275);
WIRE 16 -1 (2475 225)(2725 225);
WIRE 16 -1 (2725 275)(2725 225);
WIRE 16 -1 (2475 175)(2725 175);
WIRE 16 -1 (2725 225)(2725 175);
WIRE 16 -1 (2475 125)(2725 125);
WIRE 16 -1 (2725 175)(2725 125);
WIRE 16 -1 (2475 75)(2725 75);
WIRE 16 -1 (2725 125)(2725 75);
WIRE 16 -1 (2725 25)(2725 75);
WIRE 16 -1 (2475 25)(2725 25);
WIRE 16 -1 (-2975 3925)(-3225 3925);
WIRE 16 -1 (-3225 3925)(-3225 3875);
WIRE 16 -1 (-2975 3875)(-3225 3875);
WIRE 16 -1 (-3225 3875)(-3225 3825);
WIRE 16 -1 (-2975 3825)(-3225 3825);
WIRE 16 -1 (-3225 3825)(-3225 3775);
WIRE 16 -1 (-2975 3775)(-3225 3775);
WIRE 16 -1 (-3225 3775)(-3225 3725);
WIRE 16 -1 (-2975 3725)(-3225 3725);
WIRE 16 -1 (-3225 3725)(-3225 3675);
WIRE 16 -1 (-2975 3675)(-3225 3675);
WIRE 16 -1 (-3225 3675)(-3225 3625);
WIRE 16 -1 (-2975 3625)(-3225 3625);
WIRE 16 -1 (-3225 3625)(-3225 3575);
WIRE 16 -1 (-2975 3575)(-3225 3575);
WIRE 16 -1 (-3225 3575)(-3225 3525);
WIRE 16 -1 (-2975 3525)(-3225 3525);
WIRE 16 -1 (-3225 3525)(-3225 3475);
WIRE 16 -1 (-2975 3475)(-3225 3475);
WIRE 16 -1 (-3225 3475)(-3225 3425);
WIRE 16 -1 (-2975 3425)(-3225 3425);
WIRE 16 -1 (-3225 3425)(-3225 3375);
WIRE 16 -1 (-2975 3375)(-3225 3375);
WIRE 16 -1 (-3225 3375)(-3225 3325);
WIRE 16 -1 (-2975 3325)(-3225 3325);
WIRE 16 -1 (-3225 3325)(-3225 3275);
WIRE 16 -1 (-2975 3275)(-3225 3275);
WIRE 16 -1 (-3225 3275)(-3225 3225);
WIRE 16 -1 (-3225 3225)(-2975 3225);
WIRE 16 -1 (-3225 3225)(-3225 3175);
WIRE 16 -1 (-3225 3175)(-2975 3175);
WIRE 16 -1 (-3225 3175)(-3225 3125);
WIRE 16 -1 (-3225 3125)(-2975 3125);
WIRE 16 -1 (-3225 3125)(-3225 3075);
WIRE 16 -1 (-3225 3075)(-2975 3075);
WIRE 16 -1 (-3225 3075)(-3225 3025);
WIRE 16 -1 (-3225 3025)(-2975 3025);
WIRE 16 -1 (-3225 3025)(-3225 2975);
WIRE 16 -1 (-3225 2975)(-2975 2975);
WIRE 16 -1 (-3225 2975)(-3225 2925);
WIRE 16 -1 (-3225 2925)(-2975 2925);
WIRE 16 -1 (-3225 2925)(-3225 2875);
WIRE 16 -1 (-3225 2875)(-2975 2875);
WIRE 16 -1 (-3225 2875)(-3225 2825);
WIRE 16 -1 (-3225 2825)(-2975 2825);
WIRE 16 -1 (-3225 2825)(-3225 2775);
WIRE 16 -1 (-3225 2775)(-2975 2775);
WIRE 16 -1 (-3225 2775)(-3225 2725);
WIRE 16 -1 (-3225 2725)(-2975 2725);
WIRE 16 -1 (-3225 2725)(-3225 2675);
WIRE 16 -1 (-3225 2675)(-2975 2675);
WIRE 16 -1 (-3225 2675)(-3225 2625);
WIRE 16 -1 (-3225 2625)(-2975 2625);
WIRE 16 -1 (-3225 2625)(-3225 2575);
WIRE 16 -1 (-3225 2575)(-2975 2575);
WIRE 16 -1 (-3225 2575)(-3225 2525);
WIRE 16 -1 (-3225 2525)(-2975 2525);
WIRE 16 -1 (-3225 2525)(-3225 2475);
WIRE 16 -1 (-3225 2475)(-2975 2475);
WIRE 16 -1 (-3225 2475)(-3225 2425);
WIRE 16 -1 (-3225 2425)(-2975 2425);
WIRE 16 -1 (-3225 2425)(-3225 2375);
WIRE 16 -1 (-3225 2375)(-2975 2375);
WIRE 16 -1 (-3225 2375)(-3225 2325);
WIRE 16 -1 (-3225 2325)(-2975 2325);
WIRE 16 -1 (-3225 2325)(-3225 2275);
WIRE 16 -1 (-3225 2275)(-2975 2275);
WIRE 16 -1 (-3225 2275)(-3225 2225);
WIRE 16 -1 (-3225 2225)(-2975 2225);
WIRE 16 -1 (-3225 2225)(-3225 2175);
WIRE 16 -1 (-3225 2175)(-2975 2175);
WIRE 16 -1 (-3225 2175)(-3225 2125);
WIRE 16 -1 (-3225 2125)(-2975 2125);
WIRE 16 -1 (-3225 2125)(-3225 2075);
WIRE 16 -1 (-3225 2075)(-2975 2075);
WIRE 16 -1 (-3225 2025)(-2975 2025);
WIRE 16 -1 (-3225 2075)(-3225 2025);
WIRE 16 -1 (-3225 2025)(-3225 1975);
WIRE 16 -1 (-3225 1975)(-2975 1975);
WIRE 16 -1 (-3225 1975)(-3225 1925);
WIRE 16 -1 (-3225 1925)(-2975 1925);
WIRE 16 -1 (-3225 1925)(-3225 1875);
WIRE 16 -1 (-2975 1875)(-3225 1875);
WIRE 16 -1 (-3225 1875)(-3225 1825);
WIRE 16 -1 (-3225 1825)(-2975 1825);
WIRE 16 -1 (-3225 1825)(-3225 1775);
WIRE 16 -1 (-3225 1775)(-2975 1775);
WIRE 16 -1 (-3225 1775)(-3225 1725);
WIRE 16 -1 (-3225 1725)(-2975 1725);
WIRE 16 -1 (-3225 1725)(-3225 1675);
WIRE 16 -1 (-3225 1675)(-2975 1675);
WIRE 16 -1 (-3225 1675)(-3225 1625);
WIRE 16 -1 (-3225 1625)(-2975 1625);
WIRE 16 -1 (-3225 1625)(-3225 1575);
WIRE 16 -1 (-3225 1575)(-2975 1575);
WIRE 16 -1 (-3225 1575)(-3225 1525);
WIRE 16 -1 (-3225 1525)(-2975 1525);
WIRE 16 -1 (-3225 1525)(-3225 1475);
WIRE 16 -1 (-3225 1475)(-2975 1475);
WIRE 16 -1 (-3225 1475)(-3225 1425);
WIRE 16 -1 (-3225 1425)(-2975 1425);
WIRE 16 -1 (-3225 1425)(-3225 1375);
WIRE 16 -1 (-3225 1375)(-2975 1375);
WIRE 16 -1 (-3225 1375)(-3225 1325);
WIRE 16 -1 (-3225 1325)(-2975 1325);
WIRE 16 -1 (-3225 1325)(-3225 1275);
WIRE 16 -1 (-3225 1275)(-2975 1275);
WIRE 16 -1 (-3225 1275)(-3225 1225);
WIRE 16 -1 (-3225 1225)(-2975 1225);
WIRE 16 -1 (-3225 1225)(-3225 1175);
WIRE 16 -1 (-3225 1175)(-2975 1175);
WIRE 16 -1 (-3225 1175)(-3225 1125);
WIRE 16 -1 (-3225 1125)(-2975 1125);
WIRE 16 -1 (-3225 1125)(-3225 1075);
WIRE 16 -1 (-3225 1075)(-2975 1075);
WIRE 16 -1 (-3225 1075)(-3225 1025);
WIRE 16 -1 (-3225 1025)(-2975 1025);
WIRE 16 -1 (-3225 1025)(-3225 975);
WIRE 16 -1 (-3225 975)(-2975 975);
WIRE 16 -1 (-3225 975)(-3225 925);
WIRE 16 -1 (-3225 925)(-2975 925);
WIRE 16 -1 (-3225 925)(-3225 875);
WIRE 16 -1 (-2975 875)(-3225 875);
WIRE 16 -1 (-3225 875)(-3225 825);
WIRE 16 -1 (-3225 825)(-2975 825);
WIRE 16 -1 (-3225 825)(-3225 775);
WIRE 16 -1 (-3225 775)(-2975 775);
WIRE 16 -1 (-3225 775)(-3225 725);
WIRE 16 -1 (-3225 725)(-2975 725);
WIRE 16 -1 (-3225 725)(-3225 675);
WIRE 16 -1 (-3225 675)(-2975 675);
WIRE 16 -1 (-3225 675)(-3225 625);
WIRE 16 -1 (-3225 625)(-2975 625);
WIRE 16 -1 (-3225 625)(-3225 575);
WIRE 16 -1 (-2975 575)(-3225 575);
WIRE 16 -1 (-3225 575)(-3225 525);
WIRE 16 -1 (-3225 525)(-2975 525);
WIRE 16 -1 (-3225 525)(-3225 475);
WIRE 16 -1 (-3225 475)(-2975 475);
WIRE 16 -1 (-3225 475)(-3225 425);
WIRE 16 -1 (-3225 425)(-2975 425);
WIRE 16 -1 (-3225 425)(-3225 375);
WIRE 16 -1 (-3225 375)(-2975 375);
WIRE 16 -1 (-3225 375)(-3225 325);
WIRE 16 -1 (-3225 325)(-2975 325);
WIRE 16 -1 (-3225 325)(-3225 275);
WIRE 16 -1 (-3225 275)(-2975 275);
WIRE 16 -1 (-3225 275)(-3225 225);
WIRE 16 -1 (-2975 225)(-3225 225);
WIRE 16 -1 (-3225 225)(-3225 175);
WIRE 16 -1 (-3225 175)(-2975 175);
WIRE 16 -1 (-3225 175)(-3225 125);
WIRE 16 -1 (-3225 125)(-2975 125);
WIRE 16 -1 (-3225 125)(-3225 75);
WIRE 16 -1 (-3225 75)(-2975 75);
WIRE 16 -1 (-3225 75)(-3225 25);
WIRE 16 -1 (-3225 25)(-2975 25);
WIRE 16 -1 (-325 3925)(-575 3925);
WIRE 16 -1 (-325 3875)(-575 3875);
WIRE 16 -1 (-325 3925)(-325 3875);
WIRE 16 -1 (-325 3825)(-575 3825);
WIRE 16 -1 (-325 3875)(-325 3825);
WIRE 16 -1 (-325 3775)(-575 3775);
WIRE 16 -1 (-325 3825)(-325 3775);
WIRE 16 -1 (-575 3725)(-325 3725);
WIRE 16 -1 (-325 3725)(-325 3775);
WIRE 16 -1 (-325 3675)(-575 3675);
WIRE 16 -1 (-325 3675)(-325 3725);
WIRE 16 -1 (-325 3625)(-575 3625);
WIRE 16 -1 (-325 3675)(-325 3625);
WIRE 16 -1 (-325 3575)(-575 3575);
WIRE 16 -1 (-325 3625)(-325 3575);
WIRE 16 -1 (-325 3525)(-575 3525);
WIRE 16 -1 (-325 3575)(-325 3525);
WIRE 16 -1 (-325 3475)(-575 3475);
WIRE 16 -1 (-325 3525)(-325 3475);
WIRE 16 -1 (-325 3425)(-575 3425);
WIRE 16 -1 (-325 3475)(-325 3425);
WIRE 16 -1 (-325 3375)(-575 3375);
WIRE 16 -1 (-325 3425)(-325 3375);
WIRE 16 -1 (-325 3325)(-575 3325);
WIRE 16 -1 (-325 3375)(-325 3325);
WIRE 16 -1 (-325 3275)(-575 3275);
WIRE 16 -1 (-325 3325)(-325 3275);
WIRE 16 -1 (-575 3225)(-325 3225);
WIRE 16 -1 (-325 3275)(-325 3225);
WIRE 16 -1 (-575 3175)(-325 3175);
WIRE 16 -1 (-325 3225)(-325 3175);
WIRE 16 -1 (-575 3125)(-325 3125);
WIRE 16 -1 (-325 3175)(-325 3125);
WIRE 16 -1 (-575 3075)(-325 3075);
WIRE 16 -1 (-325 3125)(-325 3075);
WIRE 16 -1 (-575 3025)(-325 3025);
WIRE 16 -1 (-325 3075)(-325 3025);
WIRE 16 -1 (-575 2975)(-325 2975);
WIRE 16 -1 (-325 3025)(-325 2975);
WIRE 16 -1 (-575 2925)(-325 2925);
WIRE 16 -1 (-325 2975)(-325 2925);
WIRE 16 -1 (-575 2875)(-325 2875);
WIRE 16 -1 (-325 2875)(-325 2925);
WIRE 16 -1 (-575 2825)(-325 2825);
WIRE 16 -1 (-325 2875)(-325 2825);
WIRE 16 -1 (-325 2775)(-575 2775);
WIRE 16 -1 (-325 2825)(-325 2775);
WIRE 16 -1 (-325 2725)(-575 2725);
WIRE 16 -1 (-325 2775)(-325 2725);
WIRE 16 -1 (-325 2675)(-575 2675);
WIRE 16 -1 (-325 2725)(-325 2675);
WIRE 16 -1 (-325 2625)(-575 2625);
WIRE 16 -1 (-325 2675)(-325 2625);
WIRE 16 -1 (-575 2575)(-325 2575);
WIRE 16 -1 (-325 2575)(-325 2625);
WIRE 16 -1 (-325 2525)(-575 2525);
WIRE 16 -1 (-325 2525)(-325 2575);
WIRE 16 -1 (-325 2475)(-575 2475);
WIRE 16 -1 (-325 2525)(-325 2475);
WIRE 16 -1 (-325 2425)(-575 2425);
WIRE 16 -1 (-325 2475)(-325 2425);
WIRE 16 -1 (-325 2375)(-575 2375);
WIRE 16 -1 (-325 2425)(-325 2375);
WIRE 16 -1 (-325 2325)(-575 2325);
WIRE 16 -1 (-325 2375)(-325 2325);
WIRE 16 -1 (-325 2275)(-575 2275);
WIRE 16 -1 (-325 2325)(-325 2275);
WIRE 16 -1 (-325 2225)(-575 2225);
WIRE 16 -1 (-325 2275)(-325 2225);
WIRE 16 -1 (-325 2175)(-575 2175);
WIRE 16 -1 (-325 2225)(-325 2175);
WIRE 16 -1 (-325 2125)(-575 2125);
WIRE 16 -1 (-325 2175)(-325 2125);
WIRE 16 -1 (-575 2075)(-325 2075);
WIRE 16 -1 (-325 2125)(-325 2075);
WIRE 16 -1 (-575 2025)(-325 2025);
WIRE 16 -1 (-325 2075)(-325 2025);
WIRE 16 -1 (-575 1975)(-325 1975);
WIRE 16 -1 (-325 2025)(-325 1975);
WIRE 16 -1 (-575 1925)(-325 1925);
WIRE 16 -1 (-325 1975)(-325 1925);
WIRE 16 -1 (-575 1875)(-325 1875);
WIRE 16 -1 (-325 1925)(-325 1875);
WIRE 16 -1 (-575 1825)(-325 1825);
WIRE 16 -1 (-325 1875)(-325 1825);
WIRE 16 -1 (-575 1775)(-325 1775);
WIRE 16 -1 (-325 1825)(-325 1775);
WIRE 16 -1 (-575 1725)(-325 1725);
WIRE 16 -1 (-325 1725)(-325 1775);
WIRE 16 -1 (-575 1675)(-325 1675);
WIRE 16 -1 (-325 1725)(-325 1675);
WIRE 16 -1 (-325 1625)(-575 1625);
WIRE 16 -1 (-325 1675)(-325 1625);
WIRE 16 -1 (-325 1575)(-575 1575);
WIRE 16 -1 (-325 1625)(-325 1575);
WIRE 16 -1 (-325 1525)(-575 1525);
WIRE 16 -1 (-325 1575)(-325 1525);
WIRE 16 -1 (-325 1475)(-575 1475);
WIRE 16 -1 (-325 1525)(-325 1475);
WIRE 16 -1 (-575 1425)(-325 1425);
WIRE 16 -1 (-325 1425)(-325 1475);
WIRE 16 -1 (-325 1375)(-575 1375);
WIRE 16 -1 (-325 1375)(-325 1425);
WIRE 16 -1 (-325 1325)(-575 1325);
WIRE 16 -1 (-325 1375)(-325 1325);
WIRE 16 -1 (-325 1275)(-575 1275);
WIRE 16 -1 (-325 1325)(-325 1275);
WIRE 16 -1 (-575 1225)(-325 1225);
WIRE 16 -1 (-325 1275)(-325 1225);
WIRE 16 -1 (-575 1175)(-325 1175);
WIRE 16 -1 (-325 1225)(-325 1175);
WIRE 16 -1 (-575 1125)(-325 1125);
WIRE 16 -1 (-325 1175)(-325 1125);
WIRE 16 -1 (-575 1075)(-325 1075);
WIRE 16 -1 (-325 1125)(-325 1075);
WIRE 16 -1 (-575 1025)(-325 1025);
WIRE 16 -1 (-325 1075)(-325 1025);
WIRE 16 -1 (-575 975)(-325 975);
WIRE 16 -1 (-325 1025)(-325 975);
WIRE 16 -1 (-575 925)(-325 925);
WIRE 16 -1 (-325 975)(-325 925);
WIRE 16 -1 (-575 875)(-325 875);
WIRE 16 -1 (-325 875)(-325 925);
WIRE 16 -1 (-575 825)(-325 825);
WIRE 16 -1 (-325 875)(-325 825);
WIRE 16 -1 (-325 775)(-575 775);
WIRE 16 -1 (-325 825)(-325 775);
WIRE 16 -1 (-325 725)(-575 725);
WIRE 16 -1 (-325 775)(-325 725);
WIRE 16 -1 (-325 675)(-575 675);
WIRE 16 -1 (-325 725)(-325 675);
WIRE 16 -1 (-325 625)(-575 625);
WIRE 16 -1 (-325 675)(-325 625);
WIRE 16 -1 (-575 575)(-325 575);
WIRE 16 -1 (-325 575)(-325 625);
WIRE 16 -1 (-325 525)(-575 525);
WIRE 16 -1 (-325 525)(-325 575);
WIRE 16 -1 (-325 475)(-575 475);
WIRE 16 -1 (-325 525)(-325 475);
WIRE 16 -1 (-325 425)(-575 425);
WIRE 16 -1 (-325 475)(-325 425);
WIRE 16 -1 (-575 375)(-325 375);
WIRE 16 -1 (-325 425)(-325 375);
WIRE 16 -1 (-575 325)(-325 325);
WIRE 16 -1 (-325 375)(-325 325);
WIRE 16 -1 (-575 275)(-325 275);
WIRE 16 -1 (-325 325)(-325 275);
WIRE 16 -1 (-575 225)(-325 225);
WIRE 16 -1 (-325 275)(-325 225);
WIRE 16 -1 (-575 175)(-325 175);
WIRE 16 -1 (-325 225)(-325 175);
WIRE 16 -1 (-575 125)(-325 125);
WIRE 16 -1 (-325 175)(-325 125);
WIRE 16 -1 (-575 75)(-325 75);
WIRE 16 -1 (-325 125)(-325 75);
WIRE 16 -1 (-325 25)(-325 75);
WIRE 16 -1 (-575 25)(-325 25);
DOT 1 (-325 3425);
DOT 1 (5750 3875);
DOT 1 (5750 3775);
DOT 1 (5750 3825);
DOT 1 (5750 3725);
DOT 1 (5750 3625);
DOT 1 (5750 3675);
DOT 1 (5750 3475);
DOT 1 (5750 3525);
DOT 1 (5750 3575);
DOT 1 (5750 3375);
DOT 1 (5750 3425);
DOT 1 (5750 3225);
DOT 1 (5750 3325);
DOT 1 (5750 3275);
DOT 1 (5750 3175);
DOT 1 (5750 3125);
DOT 1 (5750 3075);
DOT 1 (5750 2975);
DOT 1 (5750 3025);
DOT 1 (5750 2925);
DOT 1 (5750 2875);
DOT 1 (5750 2825);
DOT 1 (5750 2775);
DOT 1 (5750 2725);
DOT 1 (5750 2625);
DOT 1 (5750 2675);
DOT 1 (5750 2575);
DOT 1 (5750 2525);
DOT 1 (5750 2475);
DOT 1 (5750 2375);
DOT 1 (5750 2425);
DOT 1 (5750 2325);
DOT 1 (5750 2275);
DOT 1 (5750 2225);
DOT 1 (5750 2125);
DOT 1 (5750 2175);
DOT 1 (5750 2075);
DOT 1 (5750 1975);
DOT 1 (5750 2025);
DOT 1 (5750 1925);
DOT 1 (5750 1875);
DOT 1 (5750 1825);
DOT 1 (5750 1775);
DOT 1 (5750 1725);
DOT 1 (5750 1675);
DOT 1 (5750 1575);
DOT 1 (5750 1625);
DOT 1 (5750 1425);
DOT 1 (5750 1475);
DOT 1 (5750 1525);
DOT 1 (5750 1325);
DOT 1 (5750 1375);
DOT 1 (5750 1175);
DOT 1 (5750 1275);
DOT 1 (5750 1225);
DOT 1 (5750 1125);
DOT 1 (5750 1075);
DOT 1 (5750 1025);
DOT 1 (5750 925);
DOT 1 (5750 975);
DOT 1 (5750 825);
DOT 1 (5750 875);
DOT 1 (5750 775);
DOT 1 (5750 675);
DOT 1 (5750 725);
DOT 1 (5750 625);
DOT 1 (5750 575);
DOT 1 (5750 525);
DOT 1 (5750 425);
DOT 1 (5750 475);
DOT 1 (5750 375);
DOT 1 (5750 325);
DOT 1 (5750 275);
DOT 1 (5750 225);
DOT 1 (5750 175);
DOT 1 (5750 75);
DOT 1 (5750 125);
DOT 1 (5750 25);
DOT 1 (2850 3875);
DOT 1 (2850 3825);
DOT 1 (2850 3775);
DOT 1 (2850 3725);
DOT 1 (2850 3625);
DOT 1 (2850 3675);
DOT 1 (2725 3875);
DOT 1 (2725 3825);
DOT 1 (2725 3775);
DOT 1 (2725 3725);
DOT 1 (2725 3625);
DOT 1 (2725 3675);
DOT 1 (2850 3575);
DOT 1 (2850 3525);
DOT 1 (2850 3475);
DOT 1 (2850 3425);
DOT 1 (2850 3375);
DOT 1 (2850 3325);
DOT 1 (2850 3275);
DOT 1 (2850 3225);
DOT 1 (2850 3175);
DOT 1 (2850 3125);
DOT 1 (2725 3575);
DOT 1 (2725 3525);
DOT 1 (2725 3475);
DOT 1 (2725 3425);
DOT 1 (2725 3375);
DOT 1 (2725 3325);
DOT 1 (2725 3275);
DOT 1 (2725 3225);
DOT 1 (2725 3175);
DOT 1 (2725 3125);
DOT 1 (2850 3075);
DOT 1 (2725 3075);
DOT 1 (2850 3025);
DOT 1 (2850 2975);
DOT 1 (2850 2925);
DOT 1 (2850 2875);
DOT 1 (2850 2825);
DOT 1 (2850 2775);
DOT 1 (2850 2725);
DOT 1 (2850 2675);
DOT 1 (2850 2625);
DOT 1 (2850 2575);
DOT 1 (2725 3025);
DOT 1 (2725 2975);
DOT 1 (2725 2925);
DOT 1 (2725 2875);
DOT 1 (2725 2825);
DOT 1 (2725 2775);
DOT 1 (2725 2725);
DOT 1 (2725 2675);
DOT 1 (2725 2625);
DOT 1 (2725 2575);
DOT 1 (2850 2525);
DOT 1 (2850 2475);
DOT 1 (2850 2425);
DOT 1 (2850 2375);
DOT 1 (2850 2325);
DOT 1 (2850 2275);
DOT 1 (2850 2225);
DOT 1 (2850 2175);
DOT 1 (2850 2125);
DOT 1 (2850 2075);
DOT 1 (2725 2525);
DOT 1 (2725 2475);
DOT 1 (2725 2425);
DOT 1 (2725 2375);
DOT 1 (2725 2325);
DOT 1 (2725 2275);
DOT 1 (2725 2225);
DOT 1 (2725 2175);
DOT 1 (2725 2125);
DOT 1 (2725 2075);
DOT 1 (2850 2025);
DOT 1 (2850 1975);
DOT 1 (2850 1925);
DOT 1 (2850 1875);
DOT 1 (2850 1825);
DOT 1 (2850 1775);
DOT 1 (2850 1725);
DOT 1 (2850 1675);
DOT 1 (2850 1575);
DOT 1 (2850 1625);
DOT 1 (2725 2025);
DOT 1 (2725 1975);
DOT 1 (2725 1925);
DOT 1 (2725 1875);
DOT 1 (2725 1825);
DOT 1 (2725 1775);
DOT 1 (2725 1725);
DOT 1 (2725 1675);
DOT 1 (2725 1575);
DOT 1 (2725 1625);
DOT 1 (2850 1525);
DOT 1 (2850 1475);
DOT 1 (2850 1425);
DOT 1 (2850 1375);
DOT 1 (2850 1325);
DOT 1 (2850 1275);
DOT 1 (2850 1225);
DOT 1 (2850 1175);
DOT 1 (2850 1125);
DOT 1 (2850 1075);
DOT 1 (2725 1525);
DOT 1 (2725 1475);
DOT 1 (2725 1425);
DOT 1 (2725 1375);
DOT 1 (2725 1325);
DOT 1 (2725 1275);
DOT 1 (2725 1225);
DOT 1 (2725 1175);
DOT 1 (2725 1125);
DOT 1 (2725 1075);
DOT 1 (2850 1025);
DOT 1 (2725 1025);
DOT 1 (2850 975);
DOT 1 (2850 925);
DOT 1 (2850 875);
DOT 1 (2850 825);
DOT 1 (2850 775);
DOT 1 (2850 725);
DOT 1 (2850 625);
DOT 1 (2850 575);
DOT 1 (2725 975);
DOT 1 (2725 925);
DOT 1 (2725 875);
DOT 1 (2725 825);
DOT 1 (2725 775);
DOT 1 (2725 725);
DOT 1 (2725 675);
DOT 1 (2725 625);
DOT 1 (2725 575);
DOT 1 (2850 525);
DOT 1 (2725 525);
DOT 1 (2850 475);
DOT 1 (2850 425);
DOT 1 (2850 375);
DOT 1 (2850 325);
DOT 1 (2850 275);
DOT 1 (2850 225);
DOT 1 (2850 175);
DOT 1 (2850 125);
DOT 1 (2850 75);
DOT 1 (2850 25);
DOT 1 (2725 425);
DOT 1 (2725 375);
DOT 1 (2725 325);
DOT 1 (2725 275);
DOT 1 (2725 225);
DOT 1 (2725 175);
DOT 1 (2725 125);
DOT 1 (2725 75);
DOT 1 (2725 25);
DOT 1 (5750 -25);
DOT 1 (2850 -25);
DOT 1 (2725 -25);
DOT 1 (-175 3875);
DOT 1 (-175 3825);
DOT 1 (-175 3775);
DOT 1 (-175 3725);
DOT 1 (-175 3625);
DOT 1 (-175 3675);
DOT 1 (-325 3875);
DOT 1 (-325 3775);
DOT 1 (-325 3825);
DOT 1 (-325 3725);
DOT 1 (-325 3675);
DOT 1 (-325 3625);
DOT 1 (-175 3575);
DOT 1 (-175 3525);
DOT 1 (-175 3475);
DOT 1 (-175 3425);
DOT 1 (-175 3375);
DOT 1 (-175 3325);
DOT 1 (-175 3275);
DOT 1 (-175 3225);
DOT 1 (-175 3175);
DOT 1 (-175 3125);
DOT 1 (-325 3475);
DOT 1 (-325 3525);
DOT 1 (-325 3575);
DOT 1 (-325 3375);
DOT 1 (-325 3225);
DOT 1 (-325 3325);
DOT 1 (-325 3275);
DOT 1 (-325 3125);
DOT 1 (-325 3175);
DOT 1 (-175 3075);
DOT 1 (-325 3075);
DOT 1 (-175 3025);
DOT 1 (-175 2975);
DOT 1 (-175 2925);
DOT 1 (-175 2875);
DOT 1 (-175 2825);
DOT 1 (-175 2775);
DOT 1 (-175 2725);
DOT 1 (-175 2675);
DOT 1 (-175 2625);
DOT 1 (-175 2575);
DOT 1 (-325 3025);
DOT 1 (-325 2975);
DOT 1 (-325 2875);
DOT 1 (-325 2925);
DOT 1 (-325 2825);
DOT 1 (-325 2725);
DOT 1 (-325 2775);
DOT 1 (-325 2625);
DOT 1 (-325 2575);
DOT 1 (-325 2675);
DOT 1 (-175 2525);
DOT 1 (-175 2475);
DOT 1 (-175 2425);
DOT 1 (-175 2375);
DOT 1 (-175 2325);
DOT 1 (-175 2275);
DOT 1 (-175 2225);
DOT 1 (-175 2175);
DOT 1 (-175 2125);
DOT 1 (-175 2075);
DOT 1 (-325 2475);
DOT 1 (-325 2525);
DOT 1 (-325 2325);
DOT 1 (-325 2375);
DOT 1 (-325 2425);
DOT 1 (-325 2225);
DOT 1 (-325 2275);
DOT 1 (-325 2175);
DOT 1 (-325 2075);
DOT 1 (-325 2125);
DOT 1 (-175 2025);
DOT 1 (-175 1975);
DOT 1 (-175 1925);
DOT 1 (-175 1875);
DOT 1 (-175 1825);
DOT 1 (-175 1775);
DOT 1 (-175 1725);
DOT 1 (-175 1675);
DOT 1 (-175 1575);
DOT 1 (-175 1625);
DOT 1 (-325 1975);
DOT 1 (-325 2025);
DOT 1 (-325 1925);
DOT 1 (-325 1875);
DOT 1 (-325 1825);
DOT 1 (-325 1775);
DOT 1 (-325 1725);
DOT 1 (-325 1675);
DOT 1 (-325 1575);
DOT 1 (-325 1625);
DOT 1 (-175 1525);
DOT 1 (-175 1475);
DOT 1 (-175 1425);
DOT 1 (-175 1375);
DOT 1 (-175 1325);
DOT 1 (-175 1275);
DOT 1 (-175 1225);
DOT 1 (-175 1175);
DOT 1 (-175 1125);
DOT 1 (-175 1075);
DOT 1 (-325 1425);
DOT 1 (-325 1475);
DOT 1 (-325 1525);
DOT 1 (-325 1325);
DOT 1 (-325 1375);
DOT 1 (-325 1175);
DOT 1 (-325 1275);
DOT 1 (-325 1225);
DOT 1 (-325 1125);
DOT 1 (-325 1075);
DOT 1 (-175 1025);
DOT 1 (-325 1025);
DOT 1 (-175 975);
DOT 1 (-175 925);
DOT 1 (-175 875);
DOT 1 (-175 825);
DOT 1 (-175 775);
DOT 1 (-175 725);
DOT 1 (-175 675);
DOT 1 (-175 625);
DOT 1 (-175 575);
DOT 1 (-325 975);
DOT 1 (-325 925);
DOT 1 (-325 825);
DOT 1 (-325 875);
DOT 1 (-325 775);
DOT 1 (-325 725);
DOT 1 (-325 675);
DOT 1 (-325 625);
DOT 1 (-325 575);
DOT 1 (-175 525);
DOT 1 (-325 525);
DOT 1 (-175 475);
DOT 1 (-175 425);
DOT 1 (-175 375);
DOT 1 (-175 325);
DOT 1 (-175 275);
DOT 1 (-175 225);
DOT 1 (-175 175);
DOT 1 (-175 125);
DOT 1 (-175 75);
DOT 1 (-175 25);
DOT 1 (-325 425);
DOT 1 (-325 475);
DOT 1 (-325 275);
DOT 1 (-325 325);
DOT 1 (-325 375);
DOT 1 (-325 175);
DOT 1 (-325 225);
DOT 1 (-325 125);
DOT 1 (-325 25);
DOT 1 (-325 75);
DOT 1 (-3225 3875);
DOT 1 (-3225 3825);
DOT 1 (-3225 3775);
DOT 1 (-3225 3725);
DOT 1 (-3225 3675);
DOT 1 (-3225 3625);
DOT 1 (-3225 3575);
DOT 1 (-3225 3525);
DOT 1 (-3225 3475);
DOT 1 (-3225 3425);
DOT 1 (-3225 3375);
DOT 1 (-3225 3325);
DOT 1 (-3225 3275);
DOT 1 (-3225 3225);
DOT 1 (-3225 3175);
DOT 1 (-3225 3125);
DOT 1 (-3225 3075);
DOT 1 (-3225 3025);
DOT 1 (-3225 2975);
DOT 1 (-3225 2925);
DOT 1 (-3225 2875);
DOT 1 (-3225 2825);
DOT 1 (-3225 2775);
DOT 1 (-3225 2725);
DOT 1 (-3225 2675);
DOT 1 (-3225 2625);
DOT 1 (-3225 2575);
DOT 1 (-3225 2525);
DOT 1 (-3225 2475);
DOT 1 (-3225 2425);
DOT 1 (-3225 2375);
DOT 1 (-3225 2325);
DOT 1 (-3225 2275);
DOT 1 (-3225 2225);
DOT 1 (-3225 2175);
DOT 1 (-3225 2125);
DOT 1 (-3225 2075);
DOT 1 (-3225 2025);
DOT 1 (-3225 1975);
DOT 1 (-3225 1925);
DOT 1 (-3225 1875);
DOT 1 (-3225 1825);
DOT 1 (-3225 1775);
DOT 1 (-3225 1725);
DOT 1 (-3225 1675);
DOT 1 (-3225 1575);
DOT 1 (-3225 1625);
DOT 1 (-3225 1525);
DOT 1 (-3225 1475);
DOT 1 (-3225 1425);
DOT 1 (-3225 1375);
DOT 1 (-3225 1325);
DOT 1 (-3225 1275);
DOT 1 (-3225 1225);
DOT 1 (-3225 1175);
DOT 1 (-3225 1125);
DOT 1 (-3225 1075);
DOT 1 (-3225 1025);
DOT 1 (-3225 975);
DOT 1 (-3225 925);
DOT 1 (-3225 875);
DOT 1 (-3225 825);
DOT 1 (-3225 775);
DOT 1 (-3225 725);
DOT 1 (-3225 675);
DOT 1 (-3225 625);
DOT 1 (-3225 575);
DOT 1 (-3225 525);
DOT 1 (-3225 475);
DOT 1 (-3225 425);
DOT 1 (-3225 375);
DOT 1 (-3225 325);
DOT 1 (-3225 275);
DOT 1 (-3225 225);
DOT 1 (-3225 175);
DOT 1 (-3225 125);
DOT 1 (-3225 75);
DOT 1 (-3225 25);
DOT 1 (-175 -25);
DOT 1 (-325 -25);
DOT 1 (-3225 -25);
DOT 1 (2850 675);
DOT 1 (2725 475);
QUIT
